FILE_TYPE = MACRO_DRAWING;
SET COLOR_WIRE YELLOW;
SET COLOR_PROP ORANGE;
SET COLOR_DOT WHITE;
SET COLOR_ARC YELLOW;
SET COLOR_BODY GREEN;
SET COLOR_NOTE PURPLE;
SET PROP_DISPLAY VALUE;
SET PAGE_NUMBER P328;
FORCEADD UNIVERSAL_GND..1
(-1175 150);
FORCEPROP 3 LASTPIN (-1175 200) SIG_NAME GND\g
J 0
(-1165 210);
DISPLAY 0.659574 (-1165 210);
PAINT MONO (-1165 210);
DISPLAY INVISIBLE (-1165 210);
FORCEPROP 2 LAST CDS_LIB pure_quanta_power
J 0
(-1175 150);
DISPLAY INVISIBLE (-1175 150);
FORCEPROP 1 LAST HDL_POWER GND
J 1
(-1150 75);
DISPLAY 0.872340 (-1150 75);
PAINT GREEN (-1150 75);
DISPLAY INVISIBLE (-1150 75);
FORCEPROP 1 LAST PATH I1
J 0
(-1100 150);
DISPLAY 0.872340 (-1100 150);
PAINT AQUA (-1100 150);
DISPLAY INVISIBLE (-1100 150);
FORCEADD OFFPAGE..2
R 2
(-2300 1150);
FORCEPROP 2 LAST $XR1 246 
J 0
(-2705 1150);
DISPLAY 0.638298 (-2705 1150);
PAINT MONO (-2705 1150);
FORCEPROP 2 LAST $XR0 123 
J 0
(-2585 1150);
DISPLAY 0.638298 (-2585 1150);
PAINT MONO (-2585 1150);
FORCEPROP 2 LAST CDS_LIB standard
J 0
(-2300 1150);
DISPLAY INVISIBLE (-2300 1150);
FORCEPROP 1 LAST OFFPAGE TRUE
J 2
(-2625 1025);
DISPLAY 0.872340 (-2625 1025);
PAINT AQUA (-2625 1025);
DISPLAY INVISIBLE (-2625 1025);
FORCEPROP 1 LAST COMMENT_BODY TRUE
J 2
(-2255 1055);
DISPLAY 0.872340 (-2255 1055);
PAINT GREEN (-2255 1055);
DISPLAY INVISIBLE (-2255 1055);
FORCEPROP 2 LAST PATH I10
J 0
(-2550 1200);
DISPLAY 0.680851 (-2550 1200);
DISPLAY INVISIBLE (-2550 1200);
FORCEADD OFFPAGE..5
(-2275 1300);
FORCEPROP 2 LAST $XR0 127 
J 0
(-2530 1300);
DISPLAY 0.638298 (-2530 1300);
PAINT MONO (-2530 1300);
FORCEPROP 2 LAST CDS_LIB standard
J 0
(-2275 1300);
DISPLAY INVISIBLE (-2275 1300);
FORCEPROP 1 LAST OFFPAGE TRUE
J 0
(-1950 1175);
DISPLAY 0.872340 (-1950 1175);
PAINT AQUA (-1950 1175);
DISPLAY INVISIBLE (-1950 1175);
FORCEPROP 1 LAST COMMENT_BODY TRUE
J 0
(-2175 1225);
DISPLAY 1.170213 (-2175 1225);
PAINT GREEN (-2175 1225);
DISPLAY INVISIBLE (-2175 1225);
FORCEPROP 2 LAST PATH I11
J 0
(-2525 1350);
DISPLAY 0.680851 (-2525 1350);
DISPLAY INVISIBLE (-2525 1350);
FORCEADD OFFPAGE..1
(-2275 1400);
FORCEPROP 2 LAST $XR0 331 
J 0
(-2557 1400);
DISPLAY 0.638298 (-2557 1400);
PAINT MONO (-2557 1400);
FORCEPROP 2 LAST CDS_LIB standard
J 0
(-2275 1400);
DISPLAY INVISIBLE (-2275 1400);
FORCEPROP 1 LAST OFFPAGE TRUE
J 0
(-1950 1275);
DISPLAY 0.872340 (-1950 1275);
PAINT AQUA (-1950 1275);
DISPLAY INVISIBLE (-1950 1275);
FORCEPROP 1 LAST COMMENT_BODY TRUE
J 0
(-2150 1300);
DISPLAY 0.872340 (-2150 1300);
PAINT GREEN (-2150 1300);
DISPLAY INVISIBLE (-2150 1300);
FORCEPROP 2 LAST PATH I12
J 0
(-2525 1450);
DISPLAY 0.680851 (-2525 1450);
DISPLAY INVISIBLE (-2525 1450);
FORCEADD OFFPAGE..1
(-2275 1450);
FORCEPROP 2 LAST $XR0 331 
J 0
(-2557 1450);
DISPLAY 0.638298 (-2557 1450);
PAINT MONO (-2557 1450);
FORCEPROP 2 LAST CDS_LIB standard
J 0
(-2275 1450);
DISPLAY INVISIBLE (-2275 1450);
FORCEPROP 1 LAST OFFPAGE TRUE
J 0
(-1950 1325);
DISPLAY 0.872340 (-1950 1325);
PAINT AQUA (-1950 1325);
DISPLAY INVISIBLE (-1950 1325);
FORCEPROP 1 LAST COMMENT_BODY TRUE
J 0
(-2150 1350);
DISPLAY 0.872340 (-2150 1350);
PAINT GREEN (-2150 1350);
DISPLAY INVISIBLE (-2150 1350);
FORCEPROP 2 LAST PATH I13
J 0
(-2525 1500);
DISPLAY 0.680851 (-2525 1500);
DISPLAY INVISIBLE (-2525 1500);
FORCEADD OFFPAGE..1
(-2275 1550);
FORCEPROP 2 LAST $XR0 320 
J 0
(-2557 1550);
DISPLAY 0.638298 (-2557 1550);
PAINT MONO (-2557 1550);
FORCEPROP 2 LAST CDS_LIB standard
J 0
(-2275 1550);
DISPLAY INVISIBLE (-2275 1550);
FORCEPROP 1 LAST OFFPAGE TRUE
J 0
(-1950 1425);
DISPLAY 0.872340 (-1950 1425);
PAINT AQUA (-1950 1425);
DISPLAY INVISIBLE (-1950 1425);
FORCEPROP 1 LAST COMMENT_BODY TRUE
J 0
(-2150 1450);
DISPLAY 0.872340 (-2150 1450);
PAINT GREEN (-2150 1450);
DISPLAY INVISIBLE (-2150 1450);
FORCEPROP 2 LAST PATH I14
J 0
(-2525 1600);
DISPLAY 0.680851 (-2525 1600);
DISPLAY INVISIBLE (-2525 1600);
FORCEADD OFFPAGE..1
(-2275 1600);
FORCEPROP 2 LAST $XR0 320 
J 0
(-2557 1600);
DISPLAY 0.638298 (-2557 1600);
PAINT MONO (-2557 1600);
FORCEPROP 2 LAST CDS_LIB standard
J 0
(-2275 1600);
DISPLAY INVISIBLE (-2275 1600);
FORCEPROP 1 LAST OFFPAGE TRUE
J 0
(-1950 1475);
DISPLAY 0.872340 (-1950 1475);
PAINT AQUA (-1950 1475);
DISPLAY INVISIBLE (-1950 1475);
FORCEPROP 1 LAST COMMENT_BODY TRUE
J 0
(-2150 1500);
DISPLAY 0.872340 (-2150 1500);
PAINT GREEN (-2150 1500);
DISPLAY INVISIBLE (-2150 1500);
FORCEPROP 2 LAST PATH I15
J 0
(-2525 1650);
DISPLAY 0.680851 (-2525 1650);
DISPLAY INVISIBLE (-2525 1650);
FORCEADD OFFPAGE..5
(-2275 1700);
FORCEPROP 2 LAST $XR0 330 
J 0
(-2530 1700);
DISPLAY 0.638298 (-2530 1700);
PAINT MONO (-2530 1700);
FORCEPROP 2 LAST CDS_LIB standard
J 0
(-2275 1700);
DISPLAY INVISIBLE (-2275 1700);
FORCEPROP 1 LAST OFFPAGE TRUE
J 0
(-1950 1575);
DISPLAY 0.872340 (-1950 1575);
PAINT AQUA (-1950 1575);
DISPLAY INVISIBLE (-1950 1575);
FORCEPROP 1 LAST COMMENT_BODY TRUE
J 0
(-2175 1625);
DISPLAY 1.170213 (-2175 1625);
PAINT GREEN (-2175 1625);
DISPLAY INVISIBLE (-2175 1625);
FORCEPROP 2 LAST PATH I16
J 0
(-2525 1750);
DISPLAY 0.680851 (-2525 1750);
DISPLAY INVISIBLE (-2525 1750);
FORCEADD OFFPAGE..2
R 2
(-2275 1750);
FORCEPROP 2 LAST $XR0 330 
J 0
(-2530 1750);
DISPLAY 0.638298 (-2530 1750);
PAINT MONO (-2530 1750);
FORCEPROP 2 LAST CDS_LIB standard
J 0
(-2275 1750);
DISPLAY INVISIBLE (-2275 1750);
FORCEPROP 1 LAST OFFPAGE TRUE
J 2
(-2600 1625);
DISPLAY 0.872340 (-2600 1625);
PAINT AQUA (-2600 1625);
DISPLAY INVISIBLE (-2600 1625);
FORCEPROP 1 LAST COMMENT_BODY TRUE
J 2
(-2230 1655);
DISPLAY 0.872340 (-2230 1655);
PAINT GREEN (-2230 1655);
DISPLAY INVISIBLE (-2230 1655);
FORCEPROP 2 LAST PATH I17
J 0
(-2525 1800);
DISPLAY 0.680851 (-2525 1800);
DISPLAY INVISIBLE (-2525 1800);
FORCEADD OFFPAGE..5
(-2275 1850);
FORCEPROP 2 LAST $XR0 319 
J 0
(-2530 1850);
DISPLAY 0.638298 (-2530 1850);
PAINT MONO (-2530 1850);
FORCEPROP 2 LAST CDS_LIB standard
J 0
(-2275 1850);
DISPLAY INVISIBLE (-2275 1850);
FORCEPROP 1 LAST OFFPAGE TRUE
J 0
(-1950 1725);
DISPLAY 0.872340 (-1950 1725);
PAINT AQUA (-1950 1725);
DISPLAY INVISIBLE (-1950 1725);
FORCEPROP 1 LAST COMMENT_BODY TRUE
J 0
(-2175 1775);
DISPLAY 1.170213 (-2175 1775);
PAINT GREEN (-2175 1775);
DISPLAY INVISIBLE (-2175 1775);
FORCEPROP 2 LAST PATH I18
J 0
(-2525 1900);
DISPLAY 0.680851 (-2525 1900);
DISPLAY INVISIBLE (-2525 1900);
FORCEADD OFFPAGE..2
R 2
(-2275 1900);
FORCEPROP 2 LAST $XR0 319 
J 0
(-2530 1900);
DISPLAY 0.638298 (-2530 1900);
PAINT MONO (-2530 1900);
FORCEPROP 2 LAST CDS_LIB standard
J 0
(-2275 1900);
DISPLAY INVISIBLE (-2275 1900);
FORCEPROP 1 LAST OFFPAGE TRUE
J 2
(-2600 1775);
DISPLAY 0.872340 (-2600 1775);
PAINT AQUA (-2600 1775);
DISPLAY INVISIBLE (-2600 1775);
FORCEPROP 1 LAST COMMENT_BODY TRUE
J 2
(-2230 1805);
DISPLAY 0.872340 (-2230 1805);
PAINT GREEN (-2230 1805);
DISPLAY INVISIBLE (-2230 1805);
FORCEPROP 2 LAST PATH I19
J 0
(-2525 1950);
DISPLAY 0.680851 (-2525 1950);
DISPLAY INVISIBLE (-2525 1950);
FORCEADD OFFPAGE..1
(-2275 550);
FORCEPROP 2 LAST $XR0 331 
J 0
(-2557 550);
DISPLAY 0.638298 (-2557 550);
PAINT MONO (-2557 550);
FORCEPROP 2 LAST CDS_LIB standard
J 0
(-2275 550);
DISPLAY INVISIBLE (-2275 550);
FORCEPROP 1 LAST OFFPAGE TRUE
J 0
(-1950 425);
DISPLAY 0.872340 (-1950 425);
PAINT AQUA (-1950 425);
DISPLAY INVISIBLE (-1950 425);
FORCEPROP 1 LAST COMMENT_BODY TRUE
J 0
(-2150 450);
DISPLAY 0.872340 (-2150 450);
PAINT GREEN (-2150 450);
DISPLAY INVISIBLE (-2150 450);
FORCEPROP 2 LAST PATH I2
J 0
(-2525 600);
DISPLAY 0.680851 (-2525 600);
DISPLAY INVISIBLE (-2525 600);
FORCEADD OFFPAGE..1
(-2275 2150);
FORCEPROP 2 LAST $XR0 331 
J 0
(-2557 2150);
DISPLAY 0.638298 (-2557 2150);
PAINT MONO (-2557 2150);
FORCEPROP 2 LAST CDS_LIB standard
J 0
(-2275 2150);
DISPLAY INVISIBLE (-2275 2150);
FORCEPROP 1 LAST OFFPAGE TRUE
J 0
(-1950 2025);
DISPLAY 0.872340 (-1950 2025);
PAINT AQUA (-1950 2025);
DISPLAY INVISIBLE (-1950 2025);
FORCEPROP 1 LAST COMMENT_BODY TRUE
J 0
(-2150 2050);
DISPLAY 0.872340 (-2150 2050);
PAINT GREEN (-2150 2050);
DISPLAY INVISIBLE (-2150 2050);
FORCEPROP 2 LAST PATH I20
J 0
(-2525 2200);
DISPLAY 0.680851 (-2525 2200);
DISPLAY INVISIBLE (-2525 2200);
FORCEADD OFFPAGE..1
(-2275 2200);
FORCEPROP 2 LAST $XR0 331 
J 0
(-2557 2200);
DISPLAY 0.638298 (-2557 2200);
PAINT MONO (-2557 2200);
FORCEPROP 2 LAST CDS_LIB standard
J 0
(-2275 2200);
DISPLAY INVISIBLE (-2275 2200);
FORCEPROP 1 LAST OFFPAGE TRUE
J 0
(-1950 2075);
DISPLAY 0.872340 (-1950 2075);
PAINT AQUA (-1950 2075);
DISPLAY INVISIBLE (-1950 2075);
FORCEPROP 1 LAST COMMENT_BODY TRUE
J 0
(-2150 2100);
DISPLAY 0.872340 (-2150 2100);
PAINT GREEN (-2150 2100);
DISPLAY INVISIBLE (-2150 2100);
FORCEPROP 2 LAST PATH I21
J 0
(-2525 2250);
DISPLAY 0.680851 (-2525 2250);
DISPLAY INVISIBLE (-2525 2250);
FORCEADD OFFPAGE..1
(-2275 2350);
FORCEPROP 2 LAST $XR0 320 
J 0
(-2557 2350);
DISPLAY 0.638298 (-2557 2350);
PAINT MONO (-2557 2350);
FORCEPROP 2 LAST CDS_LIB standard
J 0
(-2275 2350);
DISPLAY INVISIBLE (-2275 2350);
FORCEPROP 1 LAST OFFPAGE TRUE
J 0
(-1950 2225);
DISPLAY 0.872340 (-1950 2225);
PAINT AQUA (-1950 2225);
DISPLAY INVISIBLE (-1950 2225);
FORCEPROP 1 LAST COMMENT_BODY TRUE
J 0
(-2150 2250);
DISPLAY 0.872340 (-2150 2250);
PAINT GREEN (-2150 2250);
DISPLAY INVISIBLE (-2150 2250);
FORCEPROP 2 LAST PATH I22
J 0
(-2525 2400);
DISPLAY 0.680851 (-2525 2400);
DISPLAY INVISIBLE (-2525 2400);
FORCEADD OFFPAGE..1
(-2275 2300);
FORCEPROP 2 LAST $XR0 320 
J 0
(-2557 2300);
DISPLAY 0.638298 (-2557 2300);
PAINT MONO (-2557 2300);
FORCEPROP 2 LAST CDS_LIB standard
J 0
(-2275 2300);
DISPLAY INVISIBLE (-2275 2300);
FORCEPROP 1 LAST OFFPAGE TRUE
J 0
(-1950 2175);
DISPLAY 0.872340 (-1950 2175);
PAINT AQUA (-1950 2175);
DISPLAY INVISIBLE (-1950 2175);
FORCEPROP 1 LAST COMMENT_BODY TRUE
J 0
(-2150 2200);
DISPLAY 0.872340 (-2150 2200);
PAINT GREEN (-2150 2200);
DISPLAY INVISIBLE (-2150 2200);
FORCEPROP 2 LAST PATH I23
J 0
(-2525 2350);
DISPLAY 0.680851 (-2525 2350);
DISPLAY INVISIBLE (-2525 2350);
FORCEADD OFFPAGE..5
(-2275 2450);
FORCEPROP 2 LAST $XR0 330 
J 0
(-2530 2450);
DISPLAY 0.638298 (-2530 2450);
PAINT MONO (-2530 2450);
FORCEPROP 2 LAST CDS_LIB standard
J 0
(-2275 2450);
DISPLAY INVISIBLE (-2275 2450);
FORCEPROP 1 LAST OFFPAGE TRUE
J 0
(-1950 2325);
DISPLAY 0.872340 (-1950 2325);
PAINT AQUA (-1950 2325);
DISPLAY INVISIBLE (-1950 2325);
FORCEPROP 1 LAST COMMENT_BODY TRUE
J 0
(-2175 2375);
DISPLAY 1.170213 (-2175 2375);
PAINT GREEN (-2175 2375);
DISPLAY INVISIBLE (-2175 2375);
FORCEPROP 2 LAST PATH I24
J 0
(-2525 2500);
DISPLAY 0.680851 (-2525 2500);
DISPLAY INVISIBLE (-2525 2500);
FORCEADD OFFPAGE..2
R 2
(-2275 2500);
FORCEPROP 2 LAST $XR0 330 
J 0
(-2530 2500);
DISPLAY 0.638298 (-2530 2500);
PAINT MONO (-2530 2500);
FORCEPROP 2 LAST CDS_LIB standard
J 0
(-2275 2500);
DISPLAY INVISIBLE (-2275 2500);
FORCEPROP 1 LAST OFFPAGE TRUE
J 2
(-2600 2375);
DISPLAY 0.872340 (-2600 2375);
PAINT AQUA (-2600 2375);
DISPLAY INVISIBLE (-2600 2375);
FORCEPROP 1 LAST COMMENT_BODY TRUE
J 2
(-2230 2405);
DISPLAY 0.872340 (-2230 2405);
PAINT GREEN (-2230 2405);
DISPLAY INVISIBLE (-2230 2405);
FORCEPROP 2 LAST PATH I25
J 0
(-2525 2550);
DISPLAY 0.680851 (-2525 2550);
DISPLAY INVISIBLE (-2525 2550);
FORCEADD OFFPAGE..5
(-2275 2600);
FORCEPROP 2 LAST $XR0 319 
J 0
(-2530 2600);
DISPLAY 0.638298 (-2530 2600);
PAINT MONO (-2530 2600);
FORCEPROP 2 LAST CDS_LIB standard
J 0
(-2275 2600);
DISPLAY INVISIBLE (-2275 2600);
FORCEPROP 1 LAST OFFPAGE TRUE
J 0
(-1950 2475);
DISPLAY 0.872340 (-1950 2475);
PAINT AQUA (-1950 2475);
DISPLAY INVISIBLE (-1950 2475);
FORCEPROP 1 LAST COMMENT_BODY TRUE
J 0
(-2175 2525);
DISPLAY 1.170213 (-2175 2525);
PAINT GREEN (-2175 2525);
DISPLAY INVISIBLE (-2175 2525);
FORCEPROP 2 LAST PATH I26
J 0
(-2525 2650);
DISPLAY 0.680851 (-2525 2650);
DISPLAY INVISIBLE (-2525 2650);
FORCEADD OFFPAGE..1
(-2275 2750);
FORCEPROP 2 LAST $XR0 130 
J 0
(-2557 2750);
DISPLAY 0.638298 (-2557 2750);
PAINT MONO (-2557 2750);
FORCEPROP 2 LAST CDS_LIB standard
J 0
(-2275 2750);
DISPLAY INVISIBLE (-2275 2750);
FORCEPROP 1 LAST OFFPAGE TRUE
J 0
(-1950 2625);
DISPLAY 0.872340 (-1950 2625);
PAINT AQUA (-1950 2625);
DISPLAY INVISIBLE (-1950 2625);
FORCEPROP 1 LAST COMMENT_BODY TRUE
J 0
(-2150 2650);
DISPLAY 0.872340 (-2150 2650);
PAINT GREEN (-2150 2650);
DISPLAY INVISIBLE (-2150 2650);
FORCEPROP 2 LAST PATH I27
J 0
(-2525 2800);
DISPLAY 0.680851 (-2525 2800);
DISPLAY INVISIBLE (-2525 2800);
FORCEADD OFFPAGE..2
R 2
(-2275 2650);
FORCEPROP 2 LAST $XR0 319 
J 0
(-2530 2650);
DISPLAY 0.638298 (-2530 2650);
PAINT MONO (-2530 2650);
FORCEPROP 2 LAST CDS_LIB standard
J 0
(-2275 2650);
DISPLAY INVISIBLE (-2275 2650);
FORCEPROP 1 LAST OFFPAGE TRUE
J 2
(-2600 2525);
DISPLAY 0.872340 (-2600 2525);
PAINT AQUA (-2600 2525);
DISPLAY INVISIBLE (-2600 2525);
FORCEPROP 1 LAST COMMENT_BODY TRUE
J 2
(-2230 2555);
DISPLAY 0.872340 (-2230 2555);
PAINT GREEN (-2230 2555);
DISPLAY INVISIBLE (-2230 2555);
FORCEPROP 2 LAST PATH I28
J 0
(-2525 2700);
DISPLAY 0.680851 (-2525 2700);
DISPLAY INVISIBLE (-2525 2700);
FORCEADD OFFPAGE..2
R 2
(-2275 2900);
FORCEPROP 2 LAST $XR1 246 
J 0
(-2650 2900);
DISPLAY 0.638298 (-2650 2900);
PAINT MONO (-2650 2900);
FORCEPROP 2 LAST $XR0 123 
J 0
(-2530 2900);
DISPLAY 0.638298 (-2530 2900);
PAINT MONO (-2530 2900);
FORCEPROP 2 LAST CDS_LIB standard
J 0
(-2275 2900);
DISPLAY INVISIBLE (-2275 2900);
FORCEPROP 1 LAST OFFPAGE TRUE
J 2
(-2600 2775);
DISPLAY 0.872340 (-2600 2775);
PAINT AQUA (-2600 2775);
DISPLAY INVISIBLE (-2600 2775);
FORCEPROP 1 LAST COMMENT_BODY TRUE
J 2
(-2230 2805);
DISPLAY 0.872340 (-2230 2805);
PAINT GREEN (-2230 2805);
DISPLAY INVISIBLE (-2230 2805);
FORCEPROP 2 LAST PATH I29
J 0
(-2525 2950);
DISPLAY 0.680851 (-2525 2950);
DISPLAY INVISIBLE (-2525 2950);
FORCEADD OFFPAGE..1
(-2275 700);
FORCEPROP 2 LAST $XR0 320 
J 0
(-2557 700);
DISPLAY 0.638298 (-2557 700);
PAINT MONO (-2557 700);
FORCEPROP 2 LAST CDS_LIB standard
J 0
(-2275 700);
DISPLAY INVISIBLE (-2275 700);
FORCEPROP 1 LAST OFFPAGE TRUE
J 0
(-1950 575);
DISPLAY 0.872340 (-1950 575);
PAINT AQUA (-1950 575);
DISPLAY INVISIBLE (-1950 575);
FORCEPROP 1 LAST COMMENT_BODY TRUE
J 0
(-2150 600);
DISPLAY 0.872340 (-2150 600);
PAINT GREEN (-2150 600);
DISPLAY INVISIBLE (-2150 600);
FORCEPROP 2 LAST PATH I3
J 0
(-2525 750);
DISPLAY 0.680851 (-2525 750);
DISPLAY INVISIBLE (-2525 750);
FORCEADD OFFPAGE..1
(-2275 3000);
FORCEPROP 2 LAST $XR0 331 
J 0
(-2557 3000);
DISPLAY 0.638298 (-2557 3000);
PAINT MONO (-2557 3000);
FORCEPROP 2 LAST CDS_LIB standard
J 0
(-2275 3000);
DISPLAY INVISIBLE (-2275 3000);
FORCEPROP 1 LAST OFFPAGE TRUE
J 0
(-1950 2875);
DISPLAY 0.872340 (-1950 2875);
PAINT AQUA (-1950 2875);
DISPLAY INVISIBLE (-1950 2875);
FORCEPROP 1 LAST COMMENT_BODY TRUE
J 0
(-2150 2900);
DISPLAY 0.872340 (-2150 2900);
PAINT GREEN (-2150 2900);
DISPLAY INVISIBLE (-2150 2900);
FORCEPROP 2 LAST PATH I30
J 0
(-2525 3050);
DISPLAY 0.680851 (-2525 3050);
DISPLAY INVISIBLE (-2525 3050);
FORCEADD OFFPAGE..1
(-2275 3050);
FORCEPROP 2 LAST $XR0 331 
J 0
(-2557 3050);
DISPLAY 0.638298 (-2557 3050);
PAINT MONO (-2557 3050);
FORCEPROP 2 LAST CDS_LIB standard
J 0
(-2275 3050);
DISPLAY INVISIBLE (-2275 3050);
FORCEPROP 1 LAST OFFPAGE TRUE
J 0
(-1950 2925);
DISPLAY 0.872340 (-1950 2925);
PAINT AQUA (-1950 2925);
DISPLAY INVISIBLE (-1950 2925);
FORCEPROP 1 LAST COMMENT_BODY TRUE
J 0
(-2150 2950);
DISPLAY 0.872340 (-2150 2950);
PAINT GREEN (-2150 2950);
DISPLAY INVISIBLE (-2150 2950);
FORCEPROP 2 LAST PATH I31
J 0
(-2525 3100);
DISPLAY 0.680851 (-2525 3100);
DISPLAY INVISIBLE (-2525 3100);
FORCEADD OFFPAGE..1
(-2275 3150);
FORCEPROP 2 LAST $XR0 320 
J 0
(-2557 3150);
DISPLAY 0.638298 (-2557 3150);
PAINT MONO (-2557 3150);
FORCEPROP 2 LAST CDS_LIB standard
J 0
(-2275 3150);
DISPLAY INVISIBLE (-2275 3150);
FORCEPROP 1 LAST OFFPAGE TRUE
J 0
(-1950 3025);
DISPLAY 0.872340 (-1950 3025);
PAINT AQUA (-1950 3025);
DISPLAY INVISIBLE (-1950 3025);
FORCEPROP 1 LAST COMMENT_BODY TRUE
J 0
(-2150 3050);
DISPLAY 0.872340 (-2150 3050);
PAINT GREEN (-2150 3050);
DISPLAY INVISIBLE (-2150 3050);
FORCEPROP 2 LAST PATH I32
J 0
(-2525 3200);
DISPLAY 0.680851 (-2525 3200);
DISPLAY INVISIBLE (-2525 3200);
FORCEADD OFFPAGE..5
(-2275 3300);
FORCEPROP 2 LAST $XR0 330 
J 0
(-2530 3300);
DISPLAY 0.638298 (-2530 3300);
PAINT MONO (-2530 3300);
FORCEPROP 2 LAST CDS_LIB standard
J 0
(-2275 3300);
DISPLAY INVISIBLE (-2275 3300);
FORCEPROP 1 LAST OFFPAGE TRUE
J 0
(-1950 3175);
DISPLAY 0.872340 (-1950 3175);
PAINT AQUA (-1950 3175);
DISPLAY INVISIBLE (-1950 3175);
FORCEPROP 1 LAST COMMENT_BODY TRUE
J 0
(-2175 3225);
DISPLAY 1.170213 (-2175 3225);
PAINT GREEN (-2175 3225);
DISPLAY INVISIBLE (-2175 3225);
FORCEPROP 2 LAST PATH I33
J 0
(-2525 3350);
DISPLAY 0.680851 (-2525 3350);
DISPLAY INVISIBLE (-2525 3350);
FORCEADD OFFPAGE..1
(-2275 3200);
FORCEPROP 2 LAST $XR0 320 
J 0
(-2557 3200);
DISPLAY 0.638298 (-2557 3200);
PAINT MONO (-2557 3200);
FORCEPROP 2 LAST CDS_LIB standard
J 0
(-2275 3200);
DISPLAY INVISIBLE (-2275 3200);
FORCEPROP 1 LAST OFFPAGE TRUE
J 0
(-1950 3075);
DISPLAY 0.872340 (-1950 3075);
PAINT AQUA (-1950 3075);
DISPLAY INVISIBLE (-1950 3075);
FORCEPROP 1 LAST COMMENT_BODY TRUE
J 0
(-2150 3100);
DISPLAY 0.872340 (-2150 3100);
PAINT GREEN (-2150 3100);
DISPLAY INVISIBLE (-2150 3100);
FORCEPROP 2 LAST PATH I34
J 0
(-2525 3250);
DISPLAY 0.680851 (-2525 3250);
DISPLAY INVISIBLE (-2525 3250);
FORCEADD OFFPAGE..2
R 2
(-2275 3350);
FORCEPROP 2 LAST $XR0 330 
J 0
(-2530 3350);
DISPLAY 0.638298 (-2530 3350);
PAINT MONO (-2530 3350);
FORCEPROP 2 LAST CDS_LIB standard
J 0
(-2275 3350);
DISPLAY INVISIBLE (-2275 3350);
FORCEPROP 1 LAST OFFPAGE TRUE
J 2
(-2600 3225);
DISPLAY 0.872340 (-2600 3225);
PAINT AQUA (-2600 3225);
DISPLAY INVISIBLE (-2600 3225);
FORCEPROP 1 LAST COMMENT_BODY TRUE
J 2
(-2230 3255);
DISPLAY 0.872340 (-2230 3255);
PAINT GREEN (-2230 3255);
DISPLAY INVISIBLE (-2230 3255);
FORCEPROP 2 LAST PATH I35
J 0
(-2525 3400);
DISPLAY 0.680851 (-2525 3400);
DISPLAY INVISIBLE (-2525 3400);
FORCEADD OFFPAGE..5
(-2275 3450);
FORCEPROP 2 LAST $XR0 319 
J 0
(-2530 3450);
DISPLAY 0.638298 (-2530 3450);
PAINT MONO (-2530 3450);
FORCEPROP 2 LAST CDS_LIB standard
J 0
(-2275 3450);
DISPLAY INVISIBLE (-2275 3450);
FORCEPROP 1 LAST OFFPAGE TRUE
J 0
(-1950 3325);
DISPLAY 0.872340 (-1950 3325);
PAINT AQUA (-1950 3325);
DISPLAY INVISIBLE (-1950 3325);
FORCEPROP 1 LAST COMMENT_BODY TRUE
J 0
(-2175 3375);
DISPLAY 1.170213 (-2175 3375);
PAINT GREEN (-2175 3375);
DISPLAY INVISIBLE (-2175 3375);
FORCEPROP 2 LAST PATH I36
J 0
(-2525 3500);
DISPLAY 0.680851 (-2525 3500);
DISPLAY INVISIBLE (-2525 3500);
FORCEADD OFFPAGE..2
R 2
(-2275 3500);
FORCEPROP 2 LAST $XR0 319 
J 0
(-2530 3500);
DISPLAY 0.638298 (-2530 3500);
PAINT MONO (-2530 3500);
FORCEPROP 2 LAST CDS_LIB standard
J 0
(-2275 3500);
DISPLAY INVISIBLE (-2275 3500);
FORCEPROP 1 LAST OFFPAGE TRUE
J 2
(-2600 3375);
DISPLAY 0.872340 (-2600 3375);
PAINT AQUA (-2600 3375);
DISPLAY INVISIBLE (-2600 3375);
FORCEPROP 1 LAST COMMENT_BODY TRUE
J 2
(-2230 3405);
DISPLAY 0.872340 (-2230 3405);
PAINT GREEN (-2230 3405);
DISPLAY INVISIBLE (-2230 3405);
FORCEPROP 2 LAST PATH I37
J 0
(-2525 3550);
DISPLAY 0.680851 (-2525 3550);
DISPLAY INVISIBLE (-2525 3550);
FORCEADD CONN112_10137002101LF..1
(-75 2050);
FORCEPROP 1 LAST LOCATION J111
J 0
(-825 3850);
DISPLAY 0.723404 (-825 3850);
PAINT GREEN (-825 3850);
FORCEPROP 0 LAST $SEC 1
J 0
(-825 3975);
DISPLAY 0.680851 (-825 3975);
PAINT MONO (-825 3975);
DISPLAY INVISIBLE (-825 3975);
FORCEPROP 0 LAST CDS_SEC 1
J 0
(-825 3975);
DISPLAY 1.021277 (-825 3975);
DISPLAY INVISIBLE (-825 3975);
FORCEPROP 0 LASTPIN (-1000 1150) $PN A5
J 2
(-1010 1160);
DISPLAY 0.680851 (-1010 1160);
PAINT MONO (-1010 1160);
FORCEPROP 0 LASTPIN (-1000 1950) $PN A6
J 2
(-1010 1960);
DISPLAY 0.680851 (-1010 1960);
PAINT MONO (-1010 1960);
FORCEPROP 0 LASTPIN (-1000 2750) $PN A7
J 2
(-1010 2760);
DISPLAY 0.680851 (-1010 2760);
PAINT MONO (-1010 2760);
FORCEPROP 0 LASTPIN (-1000 3550) $PN A8
J 2
(-1010 3560);
DISPLAY 0.680851 (-1010 3560);
PAINT MONO (-1010 3560);
FORCEPROP 0 LASTPIN (-1000 1100) $PN B5
J 2
(-1010 1110);
DISPLAY 0.680851 (-1010 1110);
PAINT MONO (-1010 1110);
FORCEPROP 0 LASTPIN (-1000 1900) $PN B6
J 2
(-1010 1910);
DISPLAY 0.680851 (-1010 1910);
PAINT MONO (-1010 1910);
FORCEPROP 0 LASTPIN (-1000 2700) $PN B7
J 2
(-1010 2710);
DISPLAY 0.680851 (-1010 2710);
PAINT MONO (-1010 2710);
FORCEPROP 0 LASTPIN (-1000 3500) $PN B8
J 2
(-1010 3510);
DISPLAY 0.680851 (-1010 3510);
PAINT MONO (-1010 3510);
FORCEPROP 0 LASTPIN (-1000 1050) $PN C5
J 2
(-1010 1060);
DISPLAY 0.680851 (-1010 1060);
PAINT MONO (-1010 1060);
FORCEPROP 0 LASTPIN (-1000 1850) $PN C6
J 2
(-1010 1860);
DISPLAY 0.680851 (-1010 1860);
PAINT MONO (-1010 1860);
FORCEPROP 0 LASTPIN (-1000 2650) $PN C7
J 2
(-1010 2660);
DISPLAY 0.680851 (-1010 2660);
PAINT MONO (-1010 2660);
FORCEPROP 0 LASTPIN (-1000 3450) $PN C8
J 2
(-1010 3460);
DISPLAY 0.680851 (-1010 3460);
PAINT MONO (-1010 3460);
FORCEPROP 0 LASTPIN (-1000 1000) $PN D5
J 2
(-1010 1010);
DISPLAY 0.680851 (-1010 1010);
PAINT MONO (-1010 1010);
FORCEPROP 0 LASTPIN (-1000 1800) $PN D6
J 2
(-1010 1810);
DISPLAY 0.680851 (-1010 1810);
PAINT MONO (-1010 1810);
FORCEPROP 0 LASTPIN (-1000 2600) $PN D7
J 2
(-1010 2610);
DISPLAY 0.680851 (-1010 2610);
PAINT MONO (-1010 2610);
FORCEPROP 0 LASTPIN (-1000 3400) $PN D8
J 2
(-1010 3410);
DISPLAY 0.680851 (-1010 3410);
PAINT MONO (-1010 3410);
FORCEPROP 0 LASTPIN (-1000 950) $PN E5
J 2
(-1010 960);
DISPLAY 0.680851 (-1010 960);
PAINT MONO (-1010 960);
FORCEPROP 0 LASTPIN (-1000 1750) $PN E6
J 2
(-1010 1760);
DISPLAY 0.680851 (-1010 1760);
PAINT MONO (-1010 1760);
FORCEPROP 0 LASTPIN (-1000 2550) $PN E7
J 2
(-1010 2560);
DISPLAY 0.680851 (-1010 2560);
PAINT MONO (-1010 2560);
FORCEPROP 0 LASTPIN (-1000 3350) $PN E8
J 2
(-1010 3360);
DISPLAY 0.680851 (-1010 3360);
PAINT MONO (-1010 3360);
FORCEPROP 0 LASTPIN (-1000 900) $PN F5
J 2
(-1010 910);
DISPLAY 0.680851 (-1010 910);
PAINT MONO (-1010 910);
FORCEPROP 0 LASTPIN (-1000 1700) $PN F6
J 2
(-1010 1710);
DISPLAY 0.680851 (-1010 1710);
PAINT MONO (-1010 1710);
FORCEPROP 0 LASTPIN (-1000 2500) $PN F7
J 2
(-1010 2510);
DISPLAY 0.680851 (-1010 2510);
PAINT MONO (-1010 2510);
FORCEPROP 0 LASTPIN (-1000 3300) $PN F8
J 2
(-1010 3310);
DISPLAY 0.680851 (-1010 3310);
PAINT MONO (-1010 3310);
FORCEPROP 0 LASTPIN (-1000 850) $PN G5
J 2
(-1010 860);
DISPLAY 0.680851 (-1010 860);
PAINT MONO (-1010 860);
FORCEPROP 0 LASTPIN (-1000 1650) $PN G6
J 2
(-1010 1660);
DISPLAY 0.680851 (-1010 1660);
PAINT MONO (-1010 1660);
FORCEPROP 0 LASTPIN (-1000 2450) $PN G7
J 2
(-1010 2460);
DISPLAY 0.680851 (-1010 2460);
PAINT MONO (-1010 2460);
FORCEPROP 0 LASTPIN (-1000 3250) $PN G8
J 2
(-1010 3260);
DISPLAY 0.680851 (-1010 3260);
PAINT MONO (-1010 3260);
FORCEPROP 0 LASTPIN (-1000 800) $PN H5
J 2
(-1010 810);
DISPLAY 0.680851 (-1010 810);
PAINT MONO (-1010 810);
FORCEPROP 0 LASTPIN (-1000 1600) $PN H6
J 2
(-1010 1610);
DISPLAY 0.680851 (-1010 1610);
PAINT MONO (-1010 1610);
FORCEPROP 0 LASTPIN (-1000 2400) $PN H7
J 2
(-1010 2410);
DISPLAY 0.680851 (-1010 2410);
PAINT MONO (-1010 2410);
FORCEPROP 0 LASTPIN (-1000 3200) $PN H8
J 2
(-1010 3210);
DISPLAY 0.680851 (-1010 3210);
PAINT MONO (-1010 3210);
FORCEPROP 0 LASTPIN (-1000 750) $PN I5
J 2
(-1010 760);
DISPLAY 0.680851 (-1010 760);
PAINT MONO (-1010 760);
FORCEPROP 0 LASTPIN (-1000 1550) $PN I6
J 2
(-1010 1560);
DISPLAY 0.680851 (-1010 1560);
PAINT MONO (-1010 1560);
FORCEPROP 0 LASTPIN (-1000 2350) $PN I7
J 2
(-1010 2360);
DISPLAY 0.680851 (-1010 2360);
PAINT MONO (-1010 2360);
FORCEPROP 0 LASTPIN (-1000 3150) $PN I8
J 2
(-1010 3160);
DISPLAY 0.680851 (-1010 3160);
PAINT MONO (-1010 3160);
FORCEPROP 0 LASTPIN (-1000 700) $PN J5
J 2
(-1010 710);
DISPLAY 0.680851 (-1010 710);
PAINT MONO (-1010 710);
FORCEPROP 0 LASTPIN (-1000 1500) $PN J6
J 2
(-1010 1510);
DISPLAY 0.680851 (-1010 1510);
PAINT MONO (-1010 1510);
FORCEPROP 0 LASTPIN (-1000 2300) $PN J7
J 2
(-1010 2310);
DISPLAY 0.680851 (-1010 2310);
PAINT MONO (-1010 2310);
FORCEPROP 0 LASTPIN (-1000 3100) $PN J8
J 2
(-1010 3110);
DISPLAY 0.680851 (-1010 3110);
PAINT MONO (-1010 3110);
FORCEPROP 0 LASTPIN (-1000 650) $PN K5
J 2
(-1010 660);
DISPLAY 0.680851 (-1010 660);
PAINT MONO (-1010 660);
FORCEPROP 0 LASTPIN (-1000 1450) $PN K6
J 2
(-1010 1460);
DISPLAY 0.680851 (-1010 1460);
PAINT MONO (-1010 1460);
FORCEPROP 0 LASTPIN (-1000 2250) $PN K7
J 2
(-1010 2260);
DISPLAY 0.680851 (-1010 2260);
PAINT MONO (-1010 2260);
FORCEPROP 0 LASTPIN (-1000 3050) $PN K8
J 2
(-1010 3060);
DISPLAY 0.680851 (-1010 3060);
PAINT MONO (-1010 3060);
FORCEPROP 0 LASTPIN (-1000 600) $PN L5
J 2
(-1010 610);
DISPLAY 0.680851 (-1010 610);
PAINT MONO (-1010 610);
FORCEPROP 0 LASTPIN (-1000 1400) $PN L6
J 2
(-1010 1410);
DISPLAY 0.680851 (-1010 1410);
PAINT MONO (-1010 1410);
FORCEPROP 0 LASTPIN (-1000 2200) $PN L7
J 2
(-1010 2210);
DISPLAY 0.680851 (-1010 2210);
PAINT MONO (-1010 2210);
FORCEPROP 0 LASTPIN (-1000 3000) $PN L8
J 2
(-1010 3010);
DISPLAY 0.680851 (-1010 3010);
PAINT MONO (-1010 3010);
FORCEPROP 0 LASTPIN (-1000 550) $PN M5
J 2
(-1010 560);
DISPLAY 0.680851 (-1010 560);
PAINT MONO (-1010 560);
FORCEPROP 0 LASTPIN (-1000 1350) $PN M6
J 2
(-1010 1360);
DISPLAY 0.680851 (-1010 1360);
PAINT MONO (-1010 1360);
FORCEPROP 0 LASTPIN (-1000 2150) $PN M7
J 2
(-1010 2160);
DISPLAY 0.680851 (-1010 2160);
PAINT MONO (-1010 2160);
FORCEPROP 0 LASTPIN (-1000 2950) $PN M8
J 2
(-1010 2960);
DISPLAY 0.680851 (-1010 2960);
PAINT MONO (-1010 2960);
FORCEPROP 0 LASTPIN (-1000 500) $PN N5
J 2
(-1010 510);
DISPLAY 0.680851 (-1010 510);
PAINT MONO (-1010 510);
FORCEPROP 0 LASTPIN (-1000 1300) $PN N6
J 2
(-1010 1310);
DISPLAY 0.680851 (-1010 1310);
PAINT MONO (-1010 1310);
FORCEPROP 0 LASTPIN (-1000 2100) $PN N7
J 2
(-1010 2110);
DISPLAY 0.680851 (-1010 2110);
PAINT MONO (-1010 2110);
FORCEPROP 0 LASTPIN (-1000 2900) $PN N8
J 2
(-1010 2910);
DISPLAY 0.680851 (-1010 2910);
PAINT MONO (-1010 2910);
FORCEPROP 1 LAST MATERIAL IO
J 0
(-820 3732);
DISPLAY 0.723404 (-820 3732);
PAINT GREEN (-820 3732);
FORCEPROP 2 LAST PART_TYPE THLF
J 0
(-825 3925);
DISPLAY 1.021277 (-825 3925);
FORCEPROP 0 LAST VALUE CONN112_10137002-101LF
J 0
(-800 4050);
DISPLAY 1.021277 (-800 4050);
DISPLAY INVISIBLE (-800 4050);
FORCEPROP 1 LAST CDS_LMAN_SYM_OUTLINE -775,1650,775,-1650
J 0
(-75 2050);
DISPLAY 0.468085 (-75 2050);
PAINT GREEN (-75 2050);
DISPLAY INVISIBLE (-75 2050);
FORCEPROP 1 LAST NEEDS_NO_SIZE TRUE
J 0
(-75 2050);
DISPLAY 0.723404 (-75 2050);
PAINT GREEN (-75 2050);
DISPLAY INVISIBLE (-75 2050);
FORCEPROP 2 LAST CDS_LIB pure_quanta
J 0
(-75 2050);
DISPLAY INVISIBLE (-75 2050);
FORCEPROP 1 LAST PATH I38
J 0
(-75 2050);
DISPLAY 0.723404 (-75 2050);
PAINT GREEN (-75 2050);
DISPLAY INVISIBLE (-75 2050);
FORCEPROP 1 LAST PART_NUMBER DFHSB2FR012
J 0
(-825 3800);
DISPLAY 0.723404 (-825 3800);
PAINT GREEN (-825 3800);
DISPLAY INVISIBLE (-825 3800);
FORCEADD UNIVERSAL_GND..1
(3525 100);
FORCEPROP 3 LASTPIN (3525 150) SIG_NAME GND\g
J 0
(3535 160);
DISPLAY 0.659574 (3535 160);
PAINT MONO (3535 160);
DISPLAY INVISIBLE (3535 160);
FORCEPROP 2 LAST CDS_LIB pure_quanta_power
J 0
(3525 100);
DISPLAY INVISIBLE (3525 100);
FORCEPROP 1 LAST HDL_POWER GND
J 1
(3550 25);
DISPLAY 0.872340 (3550 25);
PAINT GREEN (3550 25);
DISPLAY INVISIBLE (3550 25);
FORCEPROP 1 LAST PATH I39
J 0
(3600 100);
DISPLAY 0.872340 (3600 100);
PAINT AQUA (3600 100);
DISPLAY INVISIBLE (3600 100);
FORCEADD OFFPAGE..1
(-2275 600);
FORCEPROP 2 LAST $XR0 331 
J 0
(-2557 600);
DISPLAY 0.638298 (-2557 600);
PAINT MONO (-2557 600);
FORCEPROP 2 LAST CDS_LIB standard
J 0
(-2275 600);
DISPLAY INVISIBLE (-2275 600);
FORCEPROP 1 LAST OFFPAGE TRUE
J 0
(-1950 475);
DISPLAY 0.872340 (-1950 475);
PAINT AQUA (-1950 475);
DISPLAY INVISIBLE (-1950 475);
FORCEPROP 1 LAST COMMENT_BODY TRUE
J 0
(-2150 500);
DISPLAY 0.872340 (-2150 500);
PAINT GREEN (-2150 500);
DISPLAY INVISIBLE (-2150 500);
FORCEPROP 2 LAST PATH I4
J 0
(-2525 650);
DISPLAY 0.680851 (-2525 650);
DISPLAY INVISIBLE (-2525 650);
FORCEADD OFFPAGE..1
(2450 550);
FORCEPROP 2 LAST $XR0 331 
J 0
(2168 550);
DISPLAY 0.638298 (2168 550);
PAINT MONO (2168 550);
FORCEPROP 2 LAST CDS_LIB standard
J 0
(2450 550);
DISPLAY INVISIBLE (2450 550);
FORCEPROP 1 LAST OFFPAGE TRUE
J 0
(2775 425);
DISPLAY 0.872340 (2775 425);
PAINT AQUA (2775 425);
DISPLAY INVISIBLE (2775 425);
FORCEPROP 1 LAST COMMENT_BODY TRUE
J 0
(2575 450);
DISPLAY 0.872340 (2575 450);
PAINT GREEN (2575 450);
DISPLAY INVISIBLE (2575 450);
FORCEPROP 2 LAST PATH I40
J 0
(2200 600);
DISPLAY 0.680851 (2200 600);
DISPLAY INVISIBLE (2200 600);
FORCEADD OFFPAGE..1
(2450 600);
FORCEPROP 2 LAST $XR0 331 
J 0
(2168 600);
DISPLAY 0.638298 (2168 600);
PAINT MONO (2168 600);
FORCEPROP 2 LAST CDS_LIB standard
J 0
(2450 600);
DISPLAY INVISIBLE (2450 600);
FORCEPROP 1 LAST OFFPAGE TRUE
J 0
(2775 475);
DISPLAY 0.872340 (2775 475);
PAINT AQUA (2775 475);
DISPLAY INVISIBLE (2775 475);
FORCEPROP 1 LAST COMMENT_BODY TRUE
J 0
(2575 500);
DISPLAY 0.872340 (2575 500);
PAINT GREEN (2575 500);
DISPLAY INVISIBLE (2575 500);
FORCEPROP 2 LAST PATH I41
J 0
(2200 650);
DISPLAY 0.680851 (2200 650);
DISPLAY INVISIBLE (2200 650);
FORCEADD OFFPAGE..1
(2450 700);
FORCEPROP 2 LAST $XR0 320 
J 0
(2168 700);
DISPLAY 0.638298 (2168 700);
PAINT MONO (2168 700);
FORCEPROP 2 LAST CDS_LIB standard
J 0
(2450 700);
DISPLAY INVISIBLE (2450 700);
FORCEPROP 1 LAST OFFPAGE TRUE
J 0
(2775 575);
DISPLAY 0.872340 (2775 575);
PAINT AQUA (2775 575);
DISPLAY INVISIBLE (2775 575);
FORCEPROP 1 LAST COMMENT_BODY TRUE
J 0
(2575 600);
DISPLAY 0.872340 (2575 600);
PAINT GREEN (2575 600);
DISPLAY INVISIBLE (2575 600);
FORCEPROP 2 LAST PATH I42
J 0
(2200 750);
DISPLAY 0.680851 (2200 750);
DISPLAY INVISIBLE (2200 750);
FORCEADD OFFPAGE..1
(2450 750);
FORCEPROP 2 LAST $XR0 320 
J 0
(2168 750);
DISPLAY 0.638298 (2168 750);
PAINT MONO (2168 750);
FORCEPROP 2 LAST CDS_LIB standard
J 0
(2450 750);
DISPLAY INVISIBLE (2450 750);
FORCEPROP 1 LAST OFFPAGE TRUE
J 0
(2775 625);
DISPLAY 0.872340 (2775 625);
PAINT AQUA (2775 625);
DISPLAY INVISIBLE (2775 625);
FORCEPROP 1 LAST COMMENT_BODY TRUE
J 0
(2575 650);
DISPLAY 0.872340 (2575 650);
PAINT GREEN (2575 650);
DISPLAY INVISIBLE (2575 650);
FORCEPROP 2 LAST PATH I43
J 0
(2200 800);
DISPLAY 0.680851 (2200 800);
DISPLAY INVISIBLE (2200 800);
FORCEADD OFFPAGE..2
R 2
(2450 900);
FORCEPROP 2 LAST $XR0 330 
J 0
(2195 900);
DISPLAY 0.638298 (2195 900);
PAINT MONO (2195 900);
FORCEPROP 2 LAST CDS_LIB standard
J 0
(2450 900);
DISPLAY INVISIBLE (2450 900);
FORCEPROP 1 LAST OFFPAGE TRUE
J 2
(2125 775);
DISPLAY 0.872340 (2125 775);
PAINT AQUA (2125 775);
DISPLAY INVISIBLE (2125 775);
FORCEPROP 1 LAST COMMENT_BODY TRUE
J 2
(2495 805);
DISPLAY 0.872340 (2495 805);
PAINT GREEN (2495 805);
DISPLAY INVISIBLE (2495 805);
FORCEPROP 2 LAST PATH I44
J 0
(2200 950);
DISPLAY 0.680851 (2200 950);
DISPLAY INVISIBLE (2200 950);
FORCEADD OFFPAGE..5
(2450 850);
FORCEPROP 2 LAST $XR0 330 
J 0
(2195 850);
DISPLAY 0.638298 (2195 850);
PAINT MONO (2195 850);
FORCEPROP 2 LAST CDS_LIB standard
J 0
(2450 850);
DISPLAY INVISIBLE (2450 850);
FORCEPROP 1 LAST OFFPAGE TRUE
J 0
(2775 725);
DISPLAY 0.872340 (2775 725);
PAINT AQUA (2775 725);
DISPLAY INVISIBLE (2775 725);
FORCEPROP 1 LAST COMMENT_BODY TRUE
J 0
(2550 775);
DISPLAY 1.170213 (2550 775);
PAINT GREEN (2550 775);
DISPLAY INVISIBLE (2550 775);
FORCEPROP 2 LAST PATH I45
J 0
(2200 900);
DISPLAY 0.680851 (2200 900);
DISPLAY INVISIBLE (2200 900);
FORCEADD OFFPAGE..5
(2450 1000);
FORCEPROP 2 LAST $XR0 319 
J 0
(2195 1000);
DISPLAY 0.638298 (2195 1000);
PAINT MONO (2195 1000);
FORCEPROP 2 LAST CDS_LIB standard
J 0
(2450 1000);
DISPLAY INVISIBLE (2450 1000);
FORCEPROP 1 LAST OFFPAGE TRUE
J 0
(2775 875);
DISPLAY 0.872340 (2775 875);
PAINT AQUA (2775 875);
DISPLAY INVISIBLE (2775 875);
FORCEPROP 1 LAST COMMENT_BODY TRUE
J 0
(2550 925);
DISPLAY 1.170213 (2550 925);
PAINT GREEN (2550 925);
DISPLAY INVISIBLE (2550 925);
FORCEPROP 2 LAST PATH I46
J 0
(2200 1050);
DISPLAY 0.680851 (2200 1050);
DISPLAY INVISIBLE (2200 1050);
FORCEADD OFFPAGE..2
R 2
(2450 1050);
FORCEPROP 2 LAST $XR0 319 
J 0
(2195 1050);
DISPLAY 0.638298 (2195 1050);
PAINT MONO (2195 1050);
FORCEPROP 2 LAST CDS_LIB standard
J 0
(2450 1050);
DISPLAY INVISIBLE (2450 1050);
FORCEPROP 1 LAST OFFPAGE TRUE
J 2
(2125 925);
DISPLAY 0.872340 (2125 925);
PAINT AQUA (2125 925);
DISPLAY INVISIBLE (2125 925);
FORCEPROP 1 LAST COMMENT_BODY TRUE
J 2
(2495 955);
DISPLAY 0.872340 (2495 955);
PAINT GREEN (2495 955);
DISPLAY INVISIBLE (2495 955);
FORCEPROP 2 LAST PATH I47
J 0
(2200 1100);
DISPLAY 0.680851 (2200 1100);
DISPLAY INVISIBLE (2200 1100);
FORCEADD OFFPAGE..2
R 2
(2425 1150);
FORCEPROP 2 LAST $XR1 246 
J 0
(2020 1150);
DISPLAY 0.638298 (2020 1150);
PAINT MONO (2020 1150);
FORCEPROP 2 LAST $XR0 123 
J 0
(2140 1150);
DISPLAY 0.638298 (2140 1150);
PAINT MONO (2140 1150);
FORCEPROP 2 LAST CDS_LIB standard
J 0
(2425 1150);
DISPLAY INVISIBLE (2425 1150);
FORCEPROP 1 LAST OFFPAGE TRUE
J 2
(2100 1025);
DISPLAY 0.872340 (2100 1025);
PAINT AQUA (2100 1025);
DISPLAY INVISIBLE (2100 1025);
FORCEPROP 1 LAST COMMENT_BODY TRUE
J 2
(2470 1055);
DISPLAY 0.872340 (2470 1055);
PAINT GREEN (2470 1055);
DISPLAY INVISIBLE (2470 1055);
FORCEPROP 2 LAST PATH I48
J 0
(2175 1200);
DISPLAY 0.680851 (2175 1200);
DISPLAY INVISIBLE (2175 1200);
FORCEADD OFFPAGE..5
(2450 1300);
FORCEPROP 2 LAST $XR0 126 
J 0
(2195 1300);
DISPLAY 0.638298 (2195 1300);
PAINT MONO (2195 1300);
FORCEPROP 2 LAST CDS_LIB standard
J 0
(2450 1300);
DISPLAY INVISIBLE (2450 1300);
FORCEPROP 1 LAST OFFPAGE TRUE
J 0
(2775 1175);
DISPLAY 0.872340 (2775 1175);
PAINT AQUA (2775 1175);
DISPLAY INVISIBLE (2775 1175);
FORCEPROP 1 LAST COMMENT_BODY TRUE
J 0
(2550 1225);
DISPLAY 1.170213 (2550 1225);
PAINT GREEN (2550 1225);
DISPLAY INVISIBLE (2550 1225);
FORCEPROP 2 LAST PATH I49
J 0
(2200 1350);
DISPLAY 0.680851 (2200 1350);
DISPLAY INVISIBLE (2200 1350);
FORCEADD OFFPAGE..1
(-2275 750);
FORCEPROP 2 LAST $XR0 320 
J 0
(-2557 750);
DISPLAY 0.638298 (-2557 750);
PAINT MONO (-2557 750);
FORCEPROP 2 LAST CDS_LIB standard
J 0
(-2275 750);
DISPLAY INVISIBLE (-2275 750);
FORCEPROP 1 LAST OFFPAGE TRUE
J 0
(-1950 625);
DISPLAY 0.872340 (-1950 625);
PAINT AQUA (-1950 625);
DISPLAY INVISIBLE (-1950 625);
FORCEPROP 1 LAST COMMENT_BODY TRUE
J 0
(-2150 650);
DISPLAY 0.872340 (-2150 650);
PAINT GREEN (-2150 650);
DISPLAY INVISIBLE (-2150 650);
FORCEPROP 2 LAST PATH I5
J 0
(-2525 800);
DISPLAY 0.680851 (-2525 800);
DISPLAY INVISIBLE (-2525 800);
FORCEADD OFFPAGE..1
(2450 1450);
FORCEPROP 2 LAST $XR0 331 
J 0
(2168 1450);
DISPLAY 0.638298 (2168 1450);
PAINT MONO (2168 1450);
FORCEPROP 2 LAST CDS_LIB standard
J 0
(2450 1450);
DISPLAY INVISIBLE (2450 1450);
FORCEPROP 1 LAST OFFPAGE TRUE
J 0
(2775 1325);
DISPLAY 0.872340 (2775 1325);
PAINT AQUA (2775 1325);
DISPLAY INVISIBLE (2775 1325);
FORCEPROP 1 LAST COMMENT_BODY TRUE
J 0
(2575 1350);
DISPLAY 0.872340 (2575 1350);
PAINT GREEN (2575 1350);
DISPLAY INVISIBLE (2575 1350);
FORCEPROP 2 LAST PATH I50
J 0
(2200 1500);
DISPLAY 0.680851 (2200 1500);
DISPLAY INVISIBLE (2200 1500);
FORCEADD OFFPAGE..1
(2450 1400);
FORCEPROP 2 LAST $XR0 331 
J 0
(2168 1400);
DISPLAY 0.638298 (2168 1400);
PAINT MONO (2168 1400);
FORCEPROP 2 LAST CDS_LIB standard
J 0
(2450 1400);
DISPLAY INVISIBLE (2450 1400);
FORCEPROP 1 LAST OFFPAGE TRUE
J 0
(2775 1275);
DISPLAY 0.872340 (2775 1275);
PAINT AQUA (2775 1275);
DISPLAY INVISIBLE (2775 1275);
FORCEPROP 1 LAST COMMENT_BODY TRUE
J 0
(2575 1300);
DISPLAY 0.872340 (2575 1300);
PAINT GREEN (2575 1300);
DISPLAY INVISIBLE (2575 1300);
FORCEPROP 2 LAST PATH I51
J 0
(2200 1450);
DISPLAY 0.680851 (2200 1450);
DISPLAY INVISIBLE (2200 1450);
FORCEADD OFFPAGE..1
(2450 1550);
FORCEPROP 2 LAST $XR0 320 
J 0
(2168 1550);
DISPLAY 0.638298 (2168 1550);
PAINT MONO (2168 1550);
FORCEPROP 2 LAST CDS_LIB standard
J 0
(2450 1550);
DISPLAY INVISIBLE (2450 1550);
FORCEPROP 1 LAST OFFPAGE TRUE
J 0
(2775 1425);
DISPLAY 0.872340 (2775 1425);
PAINT AQUA (2775 1425);
DISPLAY INVISIBLE (2775 1425);
FORCEPROP 1 LAST COMMENT_BODY TRUE
J 0
(2575 1450);
DISPLAY 0.872340 (2575 1450);
PAINT GREEN (2575 1450);
DISPLAY INVISIBLE (2575 1450);
FORCEPROP 2 LAST PATH I52
J 0
(2200 1600);
DISPLAY 0.680851 (2200 1600);
DISPLAY INVISIBLE (2200 1600);
FORCEADD OFFPAGE..1
(2450 1600);
FORCEPROP 2 LAST $XR0 320 
J 0
(2168 1600);
DISPLAY 0.638298 (2168 1600);
PAINT MONO (2168 1600);
FORCEPROP 2 LAST CDS_LIB standard
J 0
(2450 1600);
DISPLAY INVISIBLE (2450 1600);
FORCEPROP 1 LAST OFFPAGE TRUE
J 0
(2775 1475);
DISPLAY 0.872340 (2775 1475);
PAINT AQUA (2775 1475);
DISPLAY INVISIBLE (2775 1475);
FORCEPROP 1 LAST COMMENT_BODY TRUE
J 0
(2575 1500);
DISPLAY 0.872340 (2575 1500);
PAINT GREEN (2575 1500);
DISPLAY INVISIBLE (2575 1500);
FORCEPROP 2 LAST PATH I53
J 0
(2200 1650);
DISPLAY 0.680851 (2200 1650);
DISPLAY INVISIBLE (2200 1650);
FORCEADD OFFPAGE..5
(2450 1700);
FORCEPROP 2 LAST $XR0 330 
J 0
(2195 1700);
DISPLAY 0.638298 (2195 1700);
PAINT MONO (2195 1700);
FORCEPROP 2 LAST CDS_LIB standard
J 0
(2450 1700);
DISPLAY INVISIBLE (2450 1700);
FORCEPROP 1 LAST OFFPAGE TRUE
J 0
(2775 1575);
DISPLAY 0.872340 (2775 1575);
PAINT AQUA (2775 1575);
DISPLAY INVISIBLE (2775 1575);
FORCEPROP 1 LAST COMMENT_BODY TRUE
J 0
(2550 1625);
DISPLAY 1.170213 (2550 1625);
PAINT GREEN (2550 1625);
DISPLAY INVISIBLE (2550 1625);
FORCEPROP 2 LAST PATH I54
J 0
(2200 1750);
DISPLAY 0.680851 (2200 1750);
DISPLAY INVISIBLE (2200 1750);
FORCEADD OFFPAGE..2
R 2
(2450 1750);
FORCEPROP 2 LAST $XR0 330 
J 0
(2195 1750);
DISPLAY 0.638298 (2195 1750);
PAINT MONO (2195 1750);
FORCEPROP 2 LAST CDS_LIB standard
J 0
(2450 1750);
DISPLAY INVISIBLE (2450 1750);
FORCEPROP 1 LAST OFFPAGE TRUE
J 2
(2125 1625);
DISPLAY 0.872340 (2125 1625);
PAINT AQUA (2125 1625);
DISPLAY INVISIBLE (2125 1625);
FORCEPROP 1 LAST COMMENT_BODY TRUE
J 2
(2495 1655);
DISPLAY 0.872340 (2495 1655);
PAINT GREEN (2495 1655);
DISPLAY INVISIBLE (2495 1655);
FORCEPROP 2 LAST PATH I55
J 0
(2200 1800);
DISPLAY 0.680851 (2200 1800);
DISPLAY INVISIBLE (2200 1800);
FORCEADD OFFPAGE..2
R 2
(2450 1900);
FORCEPROP 2 LAST $XR0 319 
J 0
(2195 1900);
DISPLAY 0.638298 (2195 1900);
PAINT MONO (2195 1900);
FORCEPROP 2 LAST CDS_LIB standard
J 0
(2450 1900);
DISPLAY INVISIBLE (2450 1900);
FORCEPROP 1 LAST OFFPAGE TRUE
J 2
(2125 1775);
DISPLAY 0.872340 (2125 1775);
PAINT AQUA (2125 1775);
DISPLAY INVISIBLE (2125 1775);
FORCEPROP 1 LAST COMMENT_BODY TRUE
J 2
(2495 1805);
DISPLAY 0.872340 (2495 1805);
PAINT GREEN (2495 1805);
DISPLAY INVISIBLE (2495 1805);
FORCEPROP 2 LAST PATH I56
J 0
(2200 1950);
DISPLAY 0.680851 (2200 1950);
DISPLAY INVISIBLE (2200 1950);
FORCEADD OFFPAGE..5
(2450 1850);
FORCEPROP 2 LAST $XR0 319 
J 0
(2195 1850);
DISPLAY 0.638298 (2195 1850);
PAINT MONO (2195 1850);
FORCEPROP 2 LAST CDS_LIB standard
J 0
(2450 1850);
DISPLAY INVISIBLE (2450 1850);
FORCEPROP 1 LAST OFFPAGE TRUE
J 0
(2775 1725);
DISPLAY 0.872340 (2775 1725);
PAINT AQUA (2775 1725);
DISPLAY INVISIBLE (2775 1725);
FORCEPROP 1 LAST COMMENT_BODY TRUE
J 0
(2550 1775);
DISPLAY 1.170213 (2550 1775);
PAINT GREEN (2550 1775);
DISPLAY INVISIBLE (2550 1775);
FORCEPROP 2 LAST PATH I57
J 0
(2200 1900);
DISPLAY 0.680851 (2200 1900);
DISPLAY INVISIBLE (2200 1900);
FORCEADD OFFPAGE..1
(2450 2150);
FORCEPROP 2 LAST $XR0 331 
J 0
(2168 2150);
DISPLAY 0.638298 (2168 2150);
PAINT MONO (2168 2150);
FORCEPROP 2 LAST CDS_LIB standard
J 0
(2450 2150);
DISPLAY INVISIBLE (2450 2150);
FORCEPROP 1 LAST OFFPAGE TRUE
J 0
(2775 2025);
DISPLAY 0.872340 (2775 2025);
PAINT AQUA (2775 2025);
DISPLAY INVISIBLE (2775 2025);
FORCEPROP 1 LAST COMMENT_BODY TRUE
J 0
(2575 2050);
DISPLAY 0.872340 (2575 2050);
PAINT GREEN (2575 2050);
DISPLAY INVISIBLE (2575 2050);
FORCEPROP 2 LAST PATH I58
J 0
(2200 2200);
DISPLAY 0.680851 (2200 2200);
DISPLAY INVISIBLE (2200 2200);
FORCEADD OFFPAGE..1
(2450 2200);
FORCEPROP 2 LAST $XR0 331 
J 0
(2168 2200);
DISPLAY 0.638298 (2168 2200);
PAINT MONO (2168 2200);
FORCEPROP 2 LAST CDS_LIB standard
J 0
(2450 2200);
DISPLAY INVISIBLE (2450 2200);
FORCEPROP 1 LAST OFFPAGE TRUE
J 0
(2775 2075);
DISPLAY 0.872340 (2775 2075);
PAINT AQUA (2775 2075);
DISPLAY INVISIBLE (2775 2075);
FORCEPROP 1 LAST COMMENT_BODY TRUE
J 0
(2575 2100);
DISPLAY 0.872340 (2575 2100);
PAINT GREEN (2575 2100);
DISPLAY INVISIBLE (2575 2100);
FORCEPROP 2 LAST PATH I59
J 0
(2200 2250);
DISPLAY 0.680851 (2200 2250);
DISPLAY INVISIBLE (2200 2250);
FORCEADD OFFPAGE..5
(-2275 850);
FORCEPROP 2 LAST $XR0 330 
J 0
(-2530 850);
DISPLAY 0.638298 (-2530 850);
PAINT MONO (-2530 850);
FORCEPROP 2 LAST CDS_LIB standard
J 0
(-2275 850);
DISPLAY INVISIBLE (-2275 850);
FORCEPROP 1 LAST OFFPAGE TRUE
J 0
(-1950 725);
DISPLAY 0.872340 (-1950 725);
PAINT AQUA (-1950 725);
DISPLAY INVISIBLE (-1950 725);
FORCEPROP 1 LAST COMMENT_BODY TRUE
J 0
(-2175 775);
DISPLAY 1.170213 (-2175 775);
PAINT GREEN (-2175 775);
DISPLAY INVISIBLE (-2175 775);
FORCEPROP 2 LAST PATH I6
J 0
(-2525 900);
DISPLAY 0.680851 (-2525 900);
DISPLAY INVISIBLE (-2525 900);
FORCEADD OFFPAGE..1
(2450 2350);
FORCEPROP 2 LAST $XR0 320 
J 0
(2168 2350);
DISPLAY 0.638298 (2168 2350);
PAINT MONO (2168 2350);
FORCEPROP 2 LAST CDS_LIB standard
J 0
(2450 2350);
DISPLAY INVISIBLE (2450 2350);
FORCEPROP 1 LAST OFFPAGE TRUE
J 0
(2775 2225);
DISPLAY 0.872340 (2775 2225);
PAINT AQUA (2775 2225);
DISPLAY INVISIBLE (2775 2225);
FORCEPROP 1 LAST COMMENT_BODY TRUE
J 0
(2575 2250);
DISPLAY 0.872340 (2575 2250);
PAINT GREEN (2575 2250);
DISPLAY INVISIBLE (2575 2250);
FORCEPROP 2 LAST PATH I60
J 0
(2200 2400);
DISPLAY 0.680851 (2200 2400);
DISPLAY INVISIBLE (2200 2400);
FORCEADD OFFPAGE..1
(2450 2300);
FORCEPROP 2 LAST $XR0 320 
J 0
(2168 2300);
DISPLAY 0.638298 (2168 2300);
PAINT MONO (2168 2300);
FORCEPROP 2 LAST CDS_LIB standard
J 0
(2450 2300);
DISPLAY INVISIBLE (2450 2300);
FORCEPROP 1 LAST OFFPAGE TRUE
J 0
(2775 2175);
DISPLAY 0.872340 (2775 2175);
PAINT AQUA (2775 2175);
DISPLAY INVISIBLE (2775 2175);
FORCEPROP 1 LAST COMMENT_BODY TRUE
J 0
(2575 2200);
DISPLAY 0.872340 (2575 2200);
PAINT GREEN (2575 2200);
DISPLAY INVISIBLE (2575 2200);
FORCEPROP 2 LAST PATH I61
J 0
(2200 2350);
DISPLAY 0.680851 (2200 2350);
DISPLAY INVISIBLE (2200 2350);
FORCEADD OFFPAGE..5
(2450 2450);
FORCEPROP 2 LAST $XR0 330 
J 0
(2195 2450);
DISPLAY 0.638298 (2195 2450);
PAINT MONO (2195 2450);
FORCEPROP 2 LAST CDS_LIB standard
J 0
(2450 2450);
DISPLAY INVISIBLE (2450 2450);
FORCEPROP 1 LAST OFFPAGE TRUE
J 0
(2775 2325);
DISPLAY 0.872340 (2775 2325);
PAINT AQUA (2775 2325);
DISPLAY INVISIBLE (2775 2325);
FORCEPROP 1 LAST COMMENT_BODY TRUE
J 0
(2550 2375);
DISPLAY 1.170213 (2550 2375);
PAINT GREEN (2550 2375);
DISPLAY INVISIBLE (2550 2375);
FORCEPROP 2 LAST PATH I62
J 0
(2200 2500);
DISPLAY 0.680851 (2200 2500);
DISPLAY INVISIBLE (2200 2500);
FORCEADD OFFPAGE..2
R 2
(2450 2500);
FORCEPROP 2 LAST $XR0 330 
J 0
(2195 2500);
DISPLAY 0.638298 (2195 2500);
PAINT MONO (2195 2500);
FORCEPROP 2 LAST CDS_LIB standard
J 0
(2450 2500);
DISPLAY INVISIBLE (2450 2500);
FORCEPROP 1 LAST OFFPAGE TRUE
J 2
(2125 2375);
DISPLAY 0.872340 (2125 2375);
PAINT AQUA (2125 2375);
DISPLAY INVISIBLE (2125 2375);
FORCEPROP 1 LAST COMMENT_BODY TRUE
J 2
(2495 2405);
DISPLAY 0.872340 (2495 2405);
PAINT GREEN (2495 2405);
DISPLAY INVISIBLE (2495 2405);
FORCEPROP 2 LAST PATH I63
J 0
(2200 2550);
DISPLAY 0.680851 (2200 2550);
DISPLAY INVISIBLE (2200 2550);
FORCEADD OFFPAGE..5
(2450 2600);
FORCEPROP 2 LAST $XR0 319 
J 0
(2195 2600);
DISPLAY 0.638298 (2195 2600);
PAINT MONO (2195 2600);
FORCEPROP 2 LAST CDS_LIB standard
J 0
(2450 2600);
DISPLAY INVISIBLE (2450 2600);
FORCEPROP 1 LAST OFFPAGE TRUE
J 0
(2775 2475);
DISPLAY 0.872340 (2775 2475);
PAINT AQUA (2775 2475);
DISPLAY INVISIBLE (2775 2475);
FORCEPROP 1 LAST COMMENT_BODY TRUE
J 0
(2550 2525);
DISPLAY 1.170213 (2550 2525);
PAINT GREEN (2550 2525);
DISPLAY INVISIBLE (2550 2525);
FORCEPROP 2 LAST PATH I64
J 0
(2200 2650);
DISPLAY 0.680851 (2200 2650);
DISPLAY INVISIBLE (2200 2650);
FORCEADD OFFPAGE..2
R 2
(2450 2650);
FORCEPROP 2 LAST $XR0 319 
J 0
(2195 2650);
DISPLAY 0.638298 (2195 2650);
PAINT MONO (2195 2650);
FORCEPROP 2 LAST CDS_LIB standard
J 0
(2450 2650);
DISPLAY INVISIBLE (2450 2650);
FORCEPROP 1 LAST OFFPAGE TRUE
J 2
(2125 2525);
DISPLAY 0.872340 (2125 2525);
PAINT AQUA (2125 2525);
DISPLAY INVISIBLE (2125 2525);
FORCEPROP 1 LAST COMMENT_BODY TRUE
J 2
(2495 2555);
DISPLAY 0.872340 (2495 2555);
PAINT GREEN (2495 2555);
DISPLAY INVISIBLE (2495 2555);
FORCEPROP 2 LAST PATH I65
J 0
(2200 2700);
DISPLAY 0.680851 (2200 2700);
DISPLAY INVISIBLE (2200 2700);
FORCEADD OFFPAGE..2
R 2
(2450 2750);
FORCEPROP 2 LAST $XR1 246 
J 0
(2075 2750);
DISPLAY 0.638298 (2075 2750);
PAINT MONO (2075 2750);
FORCEPROP 2 LAST $XR0 123 
J 0
(2195 2750);
DISPLAY 0.638298 (2195 2750);
PAINT MONO (2195 2750);
FORCEPROP 2 LAST CDS_LIB standard
J 0
(2450 2750);
DISPLAY INVISIBLE (2450 2750);
FORCEPROP 1 LAST OFFPAGE TRUE
J 2
(2125 2625);
DISPLAY 0.872340 (2125 2625);
PAINT AQUA (2125 2625);
DISPLAY INVISIBLE (2125 2625);
FORCEPROP 1 LAST COMMENT_BODY TRUE
J 2
(2495 2655);
DISPLAY 0.872340 (2495 2655);
PAINT GREEN (2495 2655);
DISPLAY INVISIBLE (2495 2655);
FORCEPROP 2 LAST PATH I66
J 0
(2200 2800);
DISPLAY 0.680851 (2200 2800);
DISPLAY INVISIBLE (2200 2800);
FORCEADD OFFPAGE..1
(2450 3000);
FORCEPROP 2 LAST $XR0 331 
J 0
(2168 3000);
DISPLAY 0.638298 (2168 3000);
PAINT MONO (2168 3000);
FORCEPROP 2 LAST CDS_LIB standard
J 0
(2450 3000);
DISPLAY INVISIBLE (2450 3000);
FORCEPROP 1 LAST OFFPAGE TRUE
J 0
(2775 2875);
DISPLAY 0.872340 (2775 2875);
PAINT AQUA (2775 2875);
DISPLAY INVISIBLE (2775 2875);
FORCEPROP 1 LAST COMMENT_BODY TRUE
J 0
(2575 2900);
DISPLAY 0.872340 (2575 2900);
PAINT GREEN (2575 2900);
DISPLAY INVISIBLE (2575 2900);
FORCEPROP 2 LAST PATH I67
J 0
(2200 3050);
DISPLAY 0.680851 (2200 3050);
DISPLAY INVISIBLE (2200 3050);
FORCEADD OFFPAGE..4
R 2
(2450 2900);
FORCEPROP 2 LAST $XR0 130 
J 0
(2168 2900);
DISPLAY 0.638298 (2168 2900);
PAINT MONO (2168 2900);
FORCEPROP 2 LAST CDS_LIB standard
J 0
(2450 2900);
DISPLAY INVISIBLE (2450 2900);
FORCEPROP 1 LAST OFFPAGE TRUE
J 2
(2125 2775);
DISPLAY 0.872340 (2125 2775);
PAINT GREEN (2125 2775);
DISPLAY INVISIBLE (2125 2775);
FORCEPROP 1 LAST COMMENT_BODY TRUE
J 2
(2475 2800);
DISPLAY 0.872340 (2475 2800);
PAINT GREEN (2475 2800);
DISPLAY INVISIBLE (2475 2800);
FORCEPROP 2 LAST PATH I68
J 0
(2200 2950);
DISPLAY 0.680851 (2200 2950);
DISPLAY INVISIBLE (2200 2950);
FORCEADD OFFPAGE..1
(2450 3050);
FORCEPROP 2 LAST $XR0 331 
J 0
(2168 3050);
DISPLAY 0.638298 (2168 3050);
PAINT MONO (2168 3050);
FORCEPROP 2 LAST CDS_LIB standard
J 0
(2450 3050);
DISPLAY INVISIBLE (2450 3050);
FORCEPROP 1 LAST OFFPAGE TRUE
J 0
(2775 2925);
DISPLAY 0.872340 (2775 2925);
PAINT AQUA (2775 2925);
DISPLAY INVISIBLE (2775 2925);
FORCEPROP 1 LAST COMMENT_BODY TRUE
J 0
(2575 2950);
DISPLAY 0.872340 (2575 2950);
PAINT GREEN (2575 2950);
DISPLAY INVISIBLE (2575 2950);
FORCEPROP 2 LAST PATH I69
J 0
(2200 3100);
DISPLAY 0.680851 (2200 3100);
DISPLAY INVISIBLE (2200 3100);
FORCEADD OFFPAGE..2
R 2
(-2275 900);
FORCEPROP 2 LAST $XR0 330 
J 0
(-2530 900);
DISPLAY 0.638298 (-2530 900);
PAINT MONO (-2530 900);
FORCEPROP 2 LAST CDS_LIB standard
J 0
(-2275 900);
DISPLAY INVISIBLE (-2275 900);
FORCEPROP 1 LAST OFFPAGE TRUE
J 2
(-2600 775);
DISPLAY 0.872340 (-2600 775);
PAINT AQUA (-2600 775);
DISPLAY INVISIBLE (-2600 775);
FORCEPROP 1 LAST COMMENT_BODY TRUE
J 2
(-2230 805);
DISPLAY 0.872340 (-2230 805);
PAINT GREEN (-2230 805);
DISPLAY INVISIBLE (-2230 805);
FORCEPROP 2 LAST PATH I7
J 0
(-2525 950);
DISPLAY 0.680851 (-2525 950);
DISPLAY INVISIBLE (-2525 950);
FORCEADD OFFPAGE..1
(2450 3200);
FORCEPROP 2 LAST $XR0 320 
J 0
(2168 3200);
DISPLAY 0.638298 (2168 3200);
PAINT MONO (2168 3200);
FORCEPROP 2 LAST CDS_LIB standard
J 0
(2450 3200);
DISPLAY INVISIBLE (2450 3200);
FORCEPROP 1 LAST OFFPAGE TRUE
J 0
(2775 3075);
DISPLAY 0.872340 (2775 3075);
PAINT AQUA (2775 3075);
DISPLAY INVISIBLE (2775 3075);
FORCEPROP 1 LAST COMMENT_BODY TRUE
J 0
(2575 3100);
DISPLAY 0.872340 (2575 3100);
PAINT GREEN (2575 3100);
DISPLAY INVISIBLE (2575 3100);
FORCEPROP 2 LAST PATH I70
J 0
(2200 3250);
DISPLAY 0.680851 (2200 3250);
DISPLAY INVISIBLE (2200 3250);
FORCEADD OFFPAGE..5
(2450 3300);
FORCEPROP 2 LAST $XR0 330 
J 0
(2195 3300);
DISPLAY 0.638298 (2195 3300);
PAINT MONO (2195 3300);
FORCEPROP 2 LAST CDS_LIB standard
J 0
(2450 3300);
DISPLAY INVISIBLE (2450 3300);
FORCEPROP 1 LAST OFFPAGE TRUE
J 0
(2775 3175);
DISPLAY 0.872340 (2775 3175);
PAINT AQUA (2775 3175);
DISPLAY INVISIBLE (2775 3175);
FORCEPROP 1 LAST COMMENT_BODY TRUE
J 0
(2550 3225);
DISPLAY 1.170213 (2550 3225);
PAINT GREEN (2550 3225);
DISPLAY INVISIBLE (2550 3225);
FORCEPROP 2 LAST PATH I71
J 0
(2200 3350);
DISPLAY 0.680851 (2200 3350);
DISPLAY INVISIBLE (2200 3350);
FORCEADD OFFPAGE..1
(2450 3150);
FORCEPROP 2 LAST $XR0 320 
J 0
(2168 3150);
DISPLAY 0.638298 (2168 3150);
PAINT MONO (2168 3150);
FORCEPROP 2 LAST CDS_LIB standard
J 0
(2450 3150);
DISPLAY INVISIBLE (2450 3150);
FORCEPROP 1 LAST OFFPAGE TRUE
J 0
(2775 3025);
DISPLAY 0.872340 (2775 3025);
PAINT AQUA (2775 3025);
DISPLAY INVISIBLE (2775 3025);
FORCEPROP 1 LAST COMMENT_BODY TRUE
J 0
(2575 3050);
DISPLAY 0.872340 (2575 3050);
PAINT GREEN (2575 3050);
DISPLAY INVISIBLE (2575 3050);
FORCEPROP 2 LAST PATH I72
J 0
(2200 3200);
DISPLAY 0.680851 (2200 3200);
DISPLAY INVISIBLE (2200 3200);
FORCEADD OFFPAGE..2
R 2
(2450 3350);
FORCEPROP 2 LAST $XR0 330 
J 0
(2195 3350);
DISPLAY 0.638298 (2195 3350);
PAINT MONO (2195 3350);
FORCEPROP 2 LAST CDS_LIB standard
J 0
(2450 3350);
DISPLAY INVISIBLE (2450 3350);
FORCEPROP 1 LAST OFFPAGE TRUE
J 2
(2125 3225);
DISPLAY 0.872340 (2125 3225);
PAINT AQUA (2125 3225);
DISPLAY INVISIBLE (2125 3225);
FORCEPROP 1 LAST COMMENT_BODY TRUE
J 2
(2495 3255);
DISPLAY 0.872340 (2495 3255);
PAINT GREEN (2495 3255);
DISPLAY INVISIBLE (2495 3255);
FORCEPROP 2 LAST PATH I73
J 0
(2200 3400);
DISPLAY 0.680851 (2200 3400);
DISPLAY INVISIBLE (2200 3400);
FORCEADD OFFPAGE..5
(2450 3450);
FORCEPROP 2 LAST $XR0 319 
J 0
(2195 3450);
DISPLAY 0.638298 (2195 3450);
PAINT MONO (2195 3450);
FORCEPROP 2 LAST CDS_LIB standard
J 0
(2450 3450);
DISPLAY INVISIBLE (2450 3450);
FORCEPROP 1 LAST OFFPAGE TRUE
J 0
(2775 3325);
DISPLAY 0.872340 (2775 3325);
PAINT AQUA (2775 3325);
DISPLAY INVISIBLE (2775 3325);
FORCEPROP 1 LAST COMMENT_BODY TRUE
J 0
(2550 3375);
DISPLAY 1.170213 (2550 3375);
PAINT GREEN (2550 3375);
DISPLAY INVISIBLE (2550 3375);
FORCEPROP 2 LAST PATH I74
J 0
(2200 3500);
DISPLAY 0.680851 (2200 3500);
DISPLAY INVISIBLE (2200 3500);
FORCEADD OFFPAGE..2
R 2
(2450 3500);
FORCEPROP 2 LAST $XR0 319 
J 0
(2195 3500);
DISPLAY 0.638298 (2195 3500);
PAINT MONO (2195 3500);
FORCEPROP 2 LAST CDS_LIB standard
J 0
(2450 3500);
DISPLAY INVISIBLE (2450 3500);
FORCEPROP 1 LAST OFFPAGE TRUE
J 2
(2125 3375);
DISPLAY 0.872340 (2125 3375);
PAINT AQUA (2125 3375);
DISPLAY INVISIBLE (2125 3375);
FORCEPROP 1 LAST COMMENT_BODY TRUE
J 2
(2495 3405);
DISPLAY 0.872340 (2495 3405);
PAINT GREEN (2495 3405);
DISPLAY INVISIBLE (2495 3405);
FORCEPROP 2 LAST PATH I75
J 0
(2200 3550);
DISPLAY 0.680851 (2200 3550);
DISPLAY INVISIBLE (2200 3550);
FORCEADD CONN112_10137002101LF..2
(4675 2050);
FORCEPROP 1 LAST LOCATION J111
J 0
(3925 3875);
DISPLAY 0.723404 (3925 3875);
PAINT GREEN (3925 3875);
FORCEPROP 0 LAST $SEC 2
J 0
(3925 4000);
DISPLAY 0.680851 (3925 4000);
PAINT MONO (3925 4000);
DISPLAY INVISIBLE (3925 4000);
FORCEPROP 0 LAST CDS_SEC 2
J 0
(3925 4000);
DISPLAY 1.021277 (3925 4000);
DISPLAY INVISIBLE (3925 4000);
FORCEPROP 0 LASTPIN (3750 1150) $PN A1
J 2
(3740 1160);
DISPLAY 0.680851 (3740 1160);
PAINT MONO (3740 1160);
FORCEPROP 0 LASTPIN (3750 1950) $PN A2
J 2
(3740 1960);
DISPLAY 0.680851 (3740 1960);
PAINT MONO (3740 1960);
FORCEPROP 0 LASTPIN (3750 2750) $PN A3
J 2
(3740 2760);
DISPLAY 0.680851 (3740 2760);
PAINT MONO (3740 2760);
FORCEPROP 0 LASTPIN (3750 3550) $PN A4
J 2
(3740 3560);
DISPLAY 0.680851 (3740 3560);
PAINT MONO (3740 3560);
FORCEPROP 0 LASTPIN (3750 1100) $PN B1
J 2
(3740 1110);
DISPLAY 0.680851 (3740 1110);
PAINT MONO (3740 1110);
FORCEPROP 0 LASTPIN (3750 1900) $PN B2
J 2
(3740 1910);
DISPLAY 0.680851 (3740 1910);
PAINT MONO (3740 1910);
FORCEPROP 0 LASTPIN (3750 2700) $PN B3
J 2
(3740 2710);
DISPLAY 0.680851 (3740 2710);
PAINT MONO (3740 2710);
FORCEPROP 0 LASTPIN (3750 3500) $PN B4
J 2
(3740 3510);
DISPLAY 0.680851 (3740 3510);
PAINT MONO (3740 3510);
FORCEPROP 0 LASTPIN (3750 1050) $PN C1
J 2
(3740 1060);
DISPLAY 0.680851 (3740 1060);
PAINT MONO (3740 1060);
FORCEPROP 0 LASTPIN (3750 1850) $PN C2
J 2
(3740 1860);
DISPLAY 0.680851 (3740 1860);
PAINT MONO (3740 1860);
FORCEPROP 0 LASTPIN (3750 2650) $PN C3
J 2
(3740 2660);
DISPLAY 0.680851 (3740 2660);
PAINT MONO (3740 2660);
FORCEPROP 0 LASTPIN (3750 3450) $PN C4
J 2
(3740 3460);
DISPLAY 0.680851 (3740 3460);
PAINT MONO (3740 3460);
FORCEPROP 0 LASTPIN (3750 1000) $PN D1
J 2
(3740 1010);
DISPLAY 0.680851 (3740 1010);
PAINT MONO (3740 1010);
FORCEPROP 0 LASTPIN (3750 1800) $PN D2
J 2
(3740 1810);
DISPLAY 0.680851 (3740 1810);
PAINT MONO (3740 1810);
FORCEPROP 0 LASTPIN (3750 2600) $PN D3
J 2
(3740 2610);
DISPLAY 0.680851 (3740 2610);
PAINT MONO (3740 2610);
FORCEPROP 0 LASTPIN (3750 3400) $PN D4
J 2
(3740 3410);
DISPLAY 0.680851 (3740 3410);
PAINT MONO (3740 3410);
FORCEPROP 0 LASTPIN (3750 950) $PN E1
J 2
(3740 960);
DISPLAY 0.680851 (3740 960);
PAINT MONO (3740 960);
FORCEPROP 0 LASTPIN (3750 1750) $PN E2
J 2
(3740 1760);
DISPLAY 0.680851 (3740 1760);
PAINT MONO (3740 1760);
FORCEPROP 0 LASTPIN (3750 2550) $PN E3
J 2
(3740 2560);
DISPLAY 0.680851 (3740 2560);
PAINT MONO (3740 2560);
FORCEPROP 0 LASTPIN (3750 3350) $PN E4
J 2
(3740 3360);
DISPLAY 0.680851 (3740 3360);
PAINT MONO (3740 3360);
FORCEPROP 0 LASTPIN (3750 900) $PN F1
J 2
(3740 910);
DISPLAY 0.680851 (3740 910);
PAINT MONO (3740 910);
FORCEPROP 0 LASTPIN (3750 1700) $PN F2
J 2
(3740 1710);
DISPLAY 0.680851 (3740 1710);
PAINT MONO (3740 1710);
FORCEPROP 0 LASTPIN (3750 2500) $PN F3
J 2
(3740 2510);
DISPLAY 0.680851 (3740 2510);
PAINT MONO (3740 2510);
FORCEPROP 0 LASTPIN (3750 3300) $PN F4
J 2
(3740 3310);
DISPLAY 0.680851 (3740 3310);
PAINT MONO (3740 3310);
FORCEPROP 0 LASTPIN (3750 850) $PN G1
J 2
(3740 860);
DISPLAY 0.680851 (3740 860);
PAINT MONO (3740 860);
FORCEPROP 0 LASTPIN (3750 1650) $PN G2
J 2
(3740 1660);
DISPLAY 0.680851 (3740 1660);
PAINT MONO (3740 1660);
FORCEPROP 0 LASTPIN (3750 2450) $PN G3
J 2
(3740 2460);
DISPLAY 0.680851 (3740 2460);
PAINT MONO (3740 2460);
FORCEPROP 0 LASTPIN (3750 3250) $PN G4
J 2
(3740 3260);
DISPLAY 0.680851 (3740 3260);
PAINT MONO (3740 3260);
FORCEPROP 0 LASTPIN (3750 800) $PN H1
J 2
(3740 810);
DISPLAY 0.680851 (3740 810);
PAINT MONO (3740 810);
FORCEPROP 0 LASTPIN (3750 1600) $PN H2
J 2
(3740 1610);
DISPLAY 0.680851 (3740 1610);
PAINT MONO (3740 1610);
FORCEPROP 0 LASTPIN (3750 2400) $PN H3
J 2
(3740 2410);
DISPLAY 0.680851 (3740 2410);
PAINT MONO (3740 2410);
FORCEPROP 0 LASTPIN (3750 3200) $PN H4
J 2
(3740 3210);
DISPLAY 0.680851 (3740 3210);
PAINT MONO (3740 3210);
FORCEPROP 0 LASTPIN (3750 750) $PN I1
J 2
(3740 760);
DISPLAY 0.680851 (3740 760);
PAINT MONO (3740 760);
FORCEPROP 0 LASTPIN (3750 1550) $PN I2
J 2
(3740 1560);
DISPLAY 0.680851 (3740 1560);
PAINT MONO (3740 1560);
FORCEPROP 0 LASTPIN (3750 2350) $PN I3
J 2
(3740 2360);
DISPLAY 0.680851 (3740 2360);
PAINT MONO (3740 2360);
FORCEPROP 0 LASTPIN (3750 3150) $PN I4
J 2
(3740 3160);
DISPLAY 0.680851 (3740 3160);
PAINT MONO (3740 3160);
FORCEPROP 0 LASTPIN (3750 700) $PN J1
J 2
(3740 710);
DISPLAY 0.680851 (3740 710);
PAINT MONO (3740 710);
FORCEPROP 0 LASTPIN (3750 1500) $PN J2
J 2
(3740 1510);
DISPLAY 0.680851 (3740 1510);
PAINT MONO (3740 1510);
FORCEPROP 0 LASTPIN (3750 2300) $PN J3
J 2
(3740 2310);
DISPLAY 0.680851 (3740 2310);
PAINT MONO (3740 2310);
FORCEPROP 0 LASTPIN (3750 3100) $PN J4
J 2
(3740 3110);
DISPLAY 0.680851 (3740 3110);
PAINT MONO (3740 3110);
FORCEPROP 0 LASTPIN (3750 650) $PN K1
J 2
(3740 660);
DISPLAY 0.680851 (3740 660);
PAINT MONO (3740 660);
FORCEPROP 0 LASTPIN (3750 1450) $PN K2
J 2
(3740 1460);
DISPLAY 0.680851 (3740 1460);
PAINT MONO (3740 1460);
FORCEPROP 0 LASTPIN (3750 2250) $PN K3
J 2
(3740 2260);
DISPLAY 0.680851 (3740 2260);
PAINT MONO (3740 2260);
FORCEPROP 0 LASTPIN (3750 3050) $PN K4
J 2
(3740 3060);
DISPLAY 0.680851 (3740 3060);
PAINT MONO (3740 3060);
FORCEPROP 0 LASTPIN (3750 600) $PN L1
J 2
(3740 610);
DISPLAY 0.680851 (3740 610);
PAINT MONO (3740 610);
FORCEPROP 0 LASTPIN (3750 1400) $PN L2
J 2
(3740 1410);
DISPLAY 0.680851 (3740 1410);
PAINT MONO (3740 1410);
FORCEPROP 0 LASTPIN (3750 2200) $PN L3
J 2
(3740 2210);
DISPLAY 0.680851 (3740 2210);
PAINT MONO (3740 2210);
FORCEPROP 0 LASTPIN (3750 3000) $PN L4
J 2
(3740 3010);
DISPLAY 0.680851 (3740 3010);
PAINT MONO (3740 3010);
FORCEPROP 0 LASTPIN (3750 550) $PN M1
J 2
(3740 560);
DISPLAY 0.680851 (3740 560);
PAINT MONO (3740 560);
FORCEPROP 0 LASTPIN (3750 1350) $PN M2
J 2
(3740 1360);
DISPLAY 0.680851 (3740 1360);
PAINT MONO (3740 1360);
FORCEPROP 0 LASTPIN (3750 2150) $PN M3
J 2
(3740 2160);
DISPLAY 0.680851 (3740 2160);
PAINT MONO (3740 2160);
FORCEPROP 0 LASTPIN (3750 2950) $PN M4
J 2
(3740 2960);
DISPLAY 0.680851 (3740 2960);
PAINT MONO (3740 2960);
FORCEPROP 0 LASTPIN (3750 500) $PN N1
J 2
(3740 510);
DISPLAY 0.680851 (3740 510);
PAINT MONO (3740 510);
FORCEPROP 0 LASTPIN (3750 1300) $PN N2
J 2
(3740 1310);
DISPLAY 0.680851 (3740 1310);
PAINT MONO (3740 1310);
FORCEPROP 0 LASTPIN (3750 2100) $PN N3
J 2
(3740 2110);
DISPLAY 0.680851 (3740 2110);
PAINT MONO (3740 2110);
FORCEPROP 0 LASTPIN (3750 2900) $PN N4
J 2
(3740 2910);
DISPLAY 0.680851 (3740 2910);
PAINT MONO (3740 2910);
FORCEPROP 1 LAST MATERIAL IO
J 0
(3933 3763);
DISPLAY 0.723404 (3933 3763);
PAINT GREEN (3933 3763);
FORCEPROP 2 LAST PART_TYPE THLF
J 0
(3925 3950);
DISPLAY 1.021277 (3925 3950);
FORCEPROP 1 LAST CDS_LMAN_SYM_OUTLINE -775,1650,775,-1650
J 0
(4675 2050);
DISPLAY 0.468085 (4675 2050);
PAINT GREEN (4675 2050);
DISPLAY INVISIBLE (4675 2050);
FORCEPROP 1 LAST NEEDS_NO_SIZE TRUE
J 0
(4675 2050);
DISPLAY 0.723404 (4675 2050);
PAINT GREEN (4675 2050);
DISPLAY INVISIBLE (4675 2050);
FORCEPROP 2 LAST CDS_LIB pure_quanta
J 0
(4675 2050);
DISPLAY INVISIBLE (4675 2050);
FORCEPROP 0 LAST VALUE CONN112_10137002-101LF
J 0
(3925 3950);
DISPLAY 1.021277 (3925 3950);
DISPLAY INVISIBLE (3925 3950);
FORCEPROP 1 LAST PATH I76
J 0
(4675 2050);
DISPLAY 0.723404 (4675 2050);
PAINT GREEN (4675 2050);
DISPLAY INVISIBLE (4675 2050);
FORCEPROP 1 LAST PART_NUMBER DFHSB2FR012
J 0
(3925 3825);
DISPLAY 0.723404 (3925 3825);
PAINT GREEN (3925 3825);
DISPLAY INVISIBLE (3925 3825);
FORCEADD OFFPAGE..5
(-2275 1000);
FORCEPROP 2 LAST $XR0 319 
J 0
(-2530 1000);
DISPLAY 0.638298 (-2530 1000);
PAINT MONO (-2530 1000);
FORCEPROP 2 LAST CDS_LIB standard
J 0
(-2275 1000);
DISPLAY INVISIBLE (-2275 1000);
FORCEPROP 1 LAST OFFPAGE TRUE
J 0
(-1950 875);
DISPLAY 0.872340 (-1950 875);
PAINT AQUA (-1950 875);
DISPLAY INVISIBLE (-1950 875);
FORCEPROP 1 LAST COMMENT_BODY TRUE
J 0
(-2175 925);
DISPLAY 1.170213 (-2175 925);
PAINT GREEN (-2175 925);
DISPLAY INVISIBLE (-2175 925);
FORCEPROP 2 LAST PATH I8
J 0
(-2525 1050);
DISPLAY 0.680851 (-2525 1050);
DISPLAY INVISIBLE (-2525 1050);
FORCEADD OFFPAGE..2
R 2
(-2275 1050);
FORCEPROP 2 LAST $XR0 319 
J 0
(-2530 1050);
DISPLAY 0.638298 (-2530 1050);
PAINT MONO (-2530 1050);
FORCEPROP 2 LAST CDS_LIB standard
J 0
(-2275 1050);
DISPLAY INVISIBLE (-2275 1050);
FORCEPROP 1 LAST OFFPAGE TRUE
J 2
(-2600 925);
DISPLAY 0.872340 (-2600 925);
PAINT AQUA (-2600 925);
DISPLAY INVISIBLE (-2600 925);
FORCEPROP 1 LAST COMMENT_BODY TRUE
J 2
(-2230 955);
DISPLAY 0.872340 (-2230 955);
PAINT GREEN (-2230 955);
DISPLAY INVISIBLE (-2230 955);
FORCEPROP 2 LAST PATH I9
J 0
(-2525 1100);
DISPLAY 0.680851 (-2525 1100);
DISPLAY INVISIBLE (-2525 1100);
FORCEADD QUANTA_TITLE_BLOCK_C..1
(5650 -1650);
FORCEPROP 0 LAST CDS_CON_LAST_MODIFIED Thu Sep 14 16:12:59 2023
J 0
(3765 -1635);
PAINT MONO (3765 -1635);
DISPLAY INVISIBLE (3765 -1635);
FORCEPROP 1 LAST CUSTOM_TXT_CDS <CON_LAST_MODIFIED>
J 0
(3765 -1635);
DISPLAY 0.978723 (3765 -1635);
FORCEPROP 2 LAST CUSTOM_TXT_CDS <XR_PAGE_TITLE>
J 0
(-2240 3600);
DISPLAY 0.638298 (-2240 3600);
PAINT PINK (-2240 3600);
DISPLAY INVISIBLE (-2240 3600);
FORCEPROP 2 LAST CUSTOM_TXT_CDS <Q_NUMBER>
J 0
(4247 -1547);
DISPLAY 1.212766 (4247 -1547);
FORCEPROP 2 LAST CUSTOM_TXT_CDS <CON_PAGE_NUM> OF <CON_TOTAL_PAGES>
J 0
(5204 -1632);
DISPLAY 0.978723 (5204 -1632);
FORCEPROP 2 LAST CUSTOM_TXT_CDS <NAME_1>
J 0
(2475 -1475);
FORCEPROP 2 LAST CUSTOM_TXT_CDS <NAME_2>
J 0
(2475 -1600);
FORCEPROP 2 LAST CUSTOM_TXT_CDS <Q_PROJ>
J 0
(3268 -1548);
DISPLAY 1.212766 (3268 -1548);
FORCEPROP 2 LAST CUSTOM_TXT_CDS <Q_REV>
J 0
(5466 -1547);
DISPLAY 1.212766 (5466 -1547);
FORCEPROP 1 LAST Q_TITLE PCIE - CPU1_EXAMAX_P0/P1_X16
J 0
(-3650 -1600);
DISPLAY 1.957447 (-3650 -1600);
PAINT GREEN (-3650 -1600);
FORCEPROP 2 LAST CDS_LIB pure_quanta
J 0
(5650 -1650);
PAINT MONO (5650 -1650);
DISPLAY INVISIBLE (5650 -1650);
FORCEPROP 1 LAST CDS_LMAN_SYM_OUTLINE -9475,6775,100,-125
J 0
(5650 -1650);
DISPLAY 0.468085 (5650 -1650);
PAINT GREEN (5650 -1650);
DISPLAY INVISIBLE (5650 -1650);
FORCEPROP 2 LAST PAGE_BORDER TRUE
J 0
(-2240 3600);
DISPLAY 0.638298 (-2240 3600);
PAINT PINK (-2240 3600);
DISPLAY INVISIBLE (-2240 3600);
FORCEPROP 2 LAST CDS_XR_PAGE_TITLE CR-121 : @T6G_MB_LIB.T6G(SCH_1):PAGE121
J 0
(-2240 3600);
DISPLAY 0.638298 (-2240 3600);
PAINT PINK (-2240 3600);
DISPLAY INVISIBLE (-2240 3600);
FORCEPROP 1 LAST Q_DEPT BU9
J 1
(1887 -1601);
DISPLAY 1.957447 (1887 -1601);
PAINT GREEN (1887 -1601);
DISPLAY INVISIBLE (1887 -1601);
FORCEPROP 1 LAST COMMENT_BODY TRUE
J 0
(5662 -1663);
DISPLAY 0.978723 (5662 -1663);
PAINT GREEN (5662 -1663);
DISPLAY INVISIBLE (5662 -1663);
WIRE 16 -1 (-1000 1600)(-2225 1600);
FORCEPROP 2 LAST SIG_NAME P5E_CPU1_P0_TX_BUF_C_DN<13>
J 0
(-2085 1610);
DISPLAY 0.638298 (-2085 1610);
WIRE 16 -1 (-1000 1300)(-2225 1300);
FORCEPROP 2 LAST SIG_NAME FM_GPU_PWRGD
J 0
(-2085 1310);
DISPLAY 0.638298 (-2085 1310);
WIRE 16 -1 (3750 750)(2500 750);
FORCEPROP 2 LAST SIG_NAME P5E_CPU1_P0_TX_BUF_C_DN<8>
J 0
(2640 760);
DISPLAY 0.638298 (2640 760);
WIRE 16 -1 (3750 850)(2500 850);
FORCEPROP 2 LAST SIG_NAME P5E_CPU1_P1_RX_BUF_DP<8>
J 0
(2640 860);
DISPLAY 0.638298 (2640 860);
WIRE 16 -1 (3750 900)(2500 900);
FORCEPROP 2 LAST SIG_NAME P5E_CPU1_P1_RX_BUF_DN<8>
J 0
(2640 910);
DISPLAY 0.638298 (2640 910);
WIRE 16 -1 (3750 550)(2500 550);
FORCEPROP 2 LAST SIG_NAME P5E_CPU1_P1_TX_BUF_C_DP<8>
J 0
(2640 560);
DISPLAY 0.638298 (2640 560);
WIRE 16 -1 (3750 3550)(3525 3550);
WIRE 16 -1 (3525 3550)(3525 3400);
WIRE 16 -1 (3750 3400)(3525 3400);
WIRE 16 -1 (3525 3400)(3525 3250);
WIRE 16 -1 (3750 3250)(3525 3250);
WIRE 16 -1 (3525 3250)(3525 3100);
WIRE 16 -1 (3750 3100)(3525 3100);
WIRE 16 -1 (3525 3100)(3525 2950);
WIRE 16 -1 (3750 2950)(3525 2950);
WIRE 16 -1 (3525 2950)(3525 2700);
WIRE 16 -1 (3750 2700)(3525 2700);
WIRE 16 -1 (3525 2700)(3525 2550);
WIRE 16 -1 (3750 2550)(3525 2550);
WIRE 16 -1 (3525 2550)(3525 2400);
WIRE 16 -1 (3750 2400)(3525 2400);
WIRE 16 -1 (3525 2400)(3525 2250);
WIRE 16 -1 (3750 2250)(3525 2250);
WIRE 16 -1 (3525 2250)(3525 2100);
WIRE 16 -1 (3750 2100)(3525 2100);
WIRE 16 -1 (3525 2100)(3525 1950);
WIRE 16 -1 (3750 1950)(3525 1950);
WIRE 16 -1 (3525 1950)(3525 1800);
WIRE 16 -1 (3750 1800)(3525 1800);
WIRE 16 -1 (3525 1800)(3525 1650);
WIRE 16 -1 (3750 1650)(3525 1650);
WIRE 16 -1 (3525 1650)(3525 1500);
WIRE 16 -1 (3750 1500)(3525 1500);
WIRE 16 -1 (3525 1500)(3525 1350);
WIRE 16 -1 (3750 1350)(3525 1350);
WIRE 16 -1 (3525 1350)(3525 1100);
WIRE 16 -1 (3750 1100)(3525 1100);
WIRE 16 -1 (3525 1100)(3525 950);
WIRE 16 -1 (3750 950)(3525 950);
WIRE 16 -1 (3525 950)(3525 800);
WIRE 16 -1 (3750 800)(3525 800);
WIRE 16 -1 (3525 800)(3525 650);
WIRE 16 -1 (3750 650)(3525 650);
WIRE 16 -1 (3525 650)(3525 500);
WIRE 16 -1 (3750 500)(3525 500);
WIRE 16 -1 (3525 500)(3525 150);
WIRE 16 -1 (3750 700)(2500 700);
FORCEPROP 2 LAST SIG_NAME P5E_CPU1_P0_TX_BUF_C_DP<8>
J 0
(2640 710);
DISPLAY 0.638298 (2640 710);
WIRE 16 -1 (3750 1000)(2500 1000);
FORCEPROP 2 LAST SIG_NAME P5E_CPU1_P0_RX_BUF_DP<8>
J 0
(2640 1010);
DISPLAY 0.638298 (2640 1010);
WIRE 16 -1 (3750 1050)(2500 1050);
FORCEPROP 2 LAST SIG_NAME P5E_CPU1_P0_RX_BUF_DN<8>
J 0
(2640 1060);
DISPLAY 0.638298 (2640 1060);
WIRE 16 -1 (3750 1150)(2475 1150);
FORCEPROP 2 LAST SIG_NAME GPU_PEX_STRAP1
J 0
(2640 1160);
DISPLAY 0.638298 (2640 1160);
WIRE 16 -1 (3750 1300)(2500 1300);
FORCEPROP 2 LAST SIG_NAME GPU_PRSNT_N
J 0
(2640 1310);
DISPLAY 0.638298 (2640 1310);
WIRE 16 -1 (3750 1400)(2500 1400);
FORCEPROP 2 LAST SIG_NAME P5E_CPU1_P1_TX_BUF_C_DP<9>
J 0
(2640 1410);
DISPLAY 0.638298 (2640 1410);
WIRE 16 -1 (3750 1450)(2500 1450);
FORCEPROP 2 LAST SIG_NAME P5E_CPU1_P1_TX_BUF_C_DN<9>
J 0
(2640 1460);
DISPLAY 0.638298 (2640 1460);
WIRE 16 -1 (3750 1550)(2500 1550);
FORCEPROP 2 LAST SIG_NAME P5E_CPU1_P0_TX_BUF_C_DP<9>
J 0
(2640 1560);
DISPLAY 0.638298 (2640 1560);
WIRE 16 -1 (3750 1600)(2500 1600);
FORCEPROP 2 LAST SIG_NAME P5E_CPU1_P0_TX_BUF_C_DN<9>
J 0
(2640 1610);
DISPLAY 0.638298 (2640 1610);
WIRE 16 -1 (3750 1700)(2500 1700);
FORCEPROP 2 LAST SIG_NAME P5E_CPU1_P1_RX_BUF_DP<9>
J 0
(2640 1710);
DISPLAY 0.638298 (2640 1710);
WIRE 16 -1 (3750 1750)(2500 1750);
FORCEPROP 2 LAST SIG_NAME P5E_CPU1_P1_RX_BUF_DN<9>
J 0
(2640 1760);
DISPLAY 0.638298 (2640 1760);
WIRE 16 -1 (3750 1850)(2500 1850);
FORCEPROP 2 LAST SIG_NAME P5E_CPU1_P0_RX_BUF_DP<9>
J 0
(2640 1860);
DISPLAY 0.638298 (2640 1860);
WIRE 16 -1 (-1000 3550)(-1175 3550);
WIRE 16 -1 (-1175 3550)(-1175 3400);
WIRE 16 -1 (-1000 3400)(-1175 3400);
WIRE 16 -1 (-1175 3400)(-1175 3250);
WIRE 16 -1 (-1000 3250)(-1175 3250);
WIRE 16 -1 (-1175 3250)(-1175 3100);
WIRE 16 -1 (-1000 3100)(-1175 3100);
WIRE 16 -1 (-1175 3100)(-1175 2950);
WIRE 16 -1 (-1000 2950)(-1175 2950);
WIRE 16 -1 (-1175 2950)(-1175 2700);
WIRE 16 -1 (-1000 2700)(-1175 2700);
WIRE 16 -1 (-1175 2700)(-1175 2550);
WIRE 16 -1 (-1000 2550)(-1175 2550);
WIRE 16 -1 (-1175 2550)(-1175 2400);
WIRE 16 -1 (-1000 2400)(-1175 2400);
WIRE 16 -1 (-1175 2400)(-1175 2250);
WIRE 16 -1 (-1000 2250)(-1175 2250);
WIRE 16 -1 (-1175 2250)(-1175 2100);
WIRE 16 -1 (-1000 2100)(-1175 2100);
WIRE 16 -1 (-1175 2100)(-1175 1950);
WIRE 16 -1 (-1000 1950)(-1175 1950);
WIRE 16 -1 (-1175 1950)(-1175 1800);
WIRE 16 -1 (-1000 1800)(-1175 1800);
WIRE 16 -1 (-1175 1800)(-1175 1650);
WIRE 16 -1 (-1000 1650)(-1175 1650);
WIRE 16 -1 (-1175 1650)(-1175 1500);
WIRE 16 -1 (-1000 1500)(-1175 1500);
WIRE 16 -1 (-1175 1500)(-1175 1350);
WIRE 16 -1 (-1000 1350)(-1175 1350);
WIRE 16 -1 (-1175 1350)(-1175 1100);
WIRE 16 -1 (-1000 1100)(-1175 1100);
WIRE 16 -1 (-1175 950)(-1175 1100);
WIRE 16 -1 (-1000 950)(-1175 950);
WIRE 16 -1 (-1175 800)(-1175 950);
WIRE 16 -1 (-1000 800)(-1175 800);
WIRE 16 -1 (-1175 800)(-1175 650);
WIRE 16 -1 (-1000 650)(-1175 650);
WIRE 16 -1 (-1175 650)(-1175 500);
WIRE 16 -1 (-1000 500)(-1175 500);
WIRE 16 -1 (-1175 500)(-1175 200);
WIRE 16 -1 (3750 1900)(2500 1900);
FORCEPROP 2 LAST SIG_NAME P5E_CPU1_P0_RX_BUF_DN<9>
J 0
(2640 1910);
DISPLAY 0.638298 (2640 1910);
WIRE 16 -1 (3750 2150)(2500 2150);
FORCEPROP 2 LAST SIG_NAME P5E_CPU1_P1_TX_BUF_C_DP<10>
J 0
(2640 2160);
DISPLAY 0.638298 (2640 2160);
WIRE 16 -1 (3750 2200)(2500 2200);
FORCEPROP 2 LAST SIG_NAME P5E_CPU1_P1_TX_BUF_C_DN<10>
J 0
(2640 2210);
DISPLAY 0.638298 (2640 2210);
WIRE 16 -1 (3750 2300)(2500 2300);
FORCEPROP 2 LAST SIG_NAME P5E_CPU1_P0_TX_BUF_C_DP<10>
J 0
(2640 2310);
DISPLAY 0.638298 (2640 2310);
WIRE 16 -1 (3750 2350)(2500 2350);
FORCEPROP 2 LAST SIG_NAME P5E_CPU1_P0_TX_BUF_C_DN<10>
J 0
(2640 2360);
DISPLAY 0.638298 (2640 2360);
WIRE 16 -1 (3750 2500)(2500 2500);
FORCEPROP 2 LAST SIG_NAME P5E_CPU1_P1_RX_BUF_DN<10>
J 0
(2640 2510);
DISPLAY 0.638298 (2640 2510);
WIRE 16 -1 (3750 2600)(2500 2600);
FORCEPROP 2 LAST SIG_NAME P5E_CPU1_P0_RX_BUF_DP<10>
J 0
(2640 2610);
DISPLAY 0.638298 (2640 2610);
WIRE 16 -1 (2500 2750)(3750 2750);
FORCEPROP 2 LAST SIG_NAME GPU_BASE_ID0
J 0
(2640 2760);
DISPLAY 0.638298 (2640 2760);
WIRE 16 -1 (3750 2900)(2500 2900);
FORCEPROP 2 LAST SIG_NAME FM_GPU_PWR_EN_R_BUF
J 0
(2640 2910);
DISPLAY 0.638298 (2640 2910);
WIRE 16 -1 (3750 3000)(2500 3000);
FORCEPROP 2 LAST SIG_NAME P5E_CPU1_P1_TX_BUF_C_DP<11>
J 0
(2640 3010);
DISPLAY 0.638298 (2640 3010);
WIRE 16 -1 (3750 3050)(2500 3050);
FORCEPROP 2 LAST SIG_NAME P5E_CPU1_P1_TX_BUF_C_DN<11>
J 0
(2640 3060);
DISPLAY 0.638298 (2640 3060);
WIRE 16 -1 (3750 3150)(2500 3150);
FORCEPROP 2 LAST SIG_NAME P5E_CPU1_P0_TX_BUF_C_DP<11>
J 0
(2640 3160);
DISPLAY 0.638298 (2640 3160);
WIRE 16 -1 (3750 3200)(2500 3200);
FORCEPROP 2 LAST SIG_NAME P5E_CPU1_P0_TX_BUF_C_DN<11>
J 0
(2640 3210);
DISPLAY 0.638298 (2640 3210);
WIRE 16 -1 (3750 2650)(2500 2650);
FORCEPROP 2 LAST SIG_NAME P5E_CPU1_P0_RX_BUF_DN<10>
J 0
(2640 2660);
DISPLAY 0.638298 (2640 2660);
WIRE 16 -1 (-2225 2900)(-1000 2900);
FORCEPROP 2 LAST SIG_NAME GPU_BASE_ID1
J 0
(-2085 2910);
DISPLAY 0.638298 (-2085 2910);
WIRE 16 -1 (-1000 2750)(-2225 2750);
FORCEPROP 2 LAST SIG_NAME GPU_FPGA_RST_R_BUF_N
J 0
(-2085 2760);
DISPLAY 0.638298 (-2085 2760);
WIRE 16 -1 (-1000 2650)(-2225 2650);
FORCEPROP 2 LAST SIG_NAME P5E_CPU1_P0_RX_BUF_DN<14>
J 0
(-2085 2660);
DISPLAY 0.638298 (-2085 2660);
WIRE 16 -1 (-1000 2500)(-2225 2500);
FORCEPROP 2 LAST SIG_NAME P5E_CPU1_P1_RX_BUF_DN<14>
J 0
(-2085 2510);
DISPLAY 0.638298 (-2085 2510);
WIRE 16 -1 (-1000 2450)(-2225 2450);
FORCEPROP 2 LAST SIG_NAME P5E_CPU1_P1_RX_BUF_DP<14>
J 0
(-2085 2460);
DISPLAY 0.638298 (-2085 2460);
WIRE 16 -1 (-1000 2350)(-2225 2350);
FORCEPROP 2 LAST SIG_NAME P5E_CPU1_P0_TX_BUF_C_DN<14>
J 0
(-2085 2360);
DISPLAY 0.638298 (-2085 2360);
WIRE 16 -1 (-1000 1900)(-2225 1900);
FORCEPROP 2 LAST SIG_NAME P5E_CPU1_P0_RX_BUF_DN<13>
J 0
(-2085 1910);
DISPLAY 0.638298 (-2085 1910);
WIRE 16 -1 (-1000 1850)(-2225 1850);
FORCEPROP 2 LAST SIG_NAME P5E_CPU1_P0_RX_BUF_DP<13>
J 0
(-2085 1860);
DISPLAY 0.638298 (-2085 1860);
WIRE 16 -1 (-1000 1750)(-2225 1750);
FORCEPROP 2 LAST SIG_NAME P5E_CPU1_P1_RX_BUF_DN<13>
J 0
(-2085 1760);
DISPLAY 0.638298 (-2085 1760);
WIRE 16 -1 (-1000 1550)(-2225 1550);
FORCEPROP 2 LAST SIG_NAME P5E_CPU1_P0_TX_BUF_C_DP<13>
J 0
(-2085 1560);
DISPLAY 0.638298 (-2085 1560);
WIRE 16 -1 (-1000 1400)(-2225 1400);
FORCEPROP 2 LAST SIG_NAME P5E_CPU1_P1_TX_BUF_C_DP<13>
J 0
(-2085 1410);
DISPLAY 0.638298 (-2085 1410);
WIRE 16 -1 (-2250 1150)(-1000 1150);
FORCEPROP 2 LAST SIG_NAME GPU_PEX_STRAP0
J 0
(-2085 1160);
DISPLAY 0.638298 (-2085 1160);
WIRE 16 -1 (-1000 1050)(-2225 1050);
FORCEPROP 2 LAST SIG_NAME P5E_CPU1_P0_RX_BUF_DN<12>
J 0
(-2085 1060);
DISPLAY 0.638298 (-2085 1060);
WIRE 16 -1 (-1000 550)(-2225 550);
FORCEPROP 2 LAST SIG_NAME P5E_CPU1_P1_TX_BUF_C_DP<12>
J 0
(-2085 560);
DISPLAY 0.638298 (-2085 560);
WIRE 16 -1 (-1000 600)(-2225 600);
FORCEPROP 2 LAST SIG_NAME P5E_CPU1_P1_TX_BUF_C_DN<12>
J 0
(-2085 610);
DISPLAY 0.638298 (-2085 610);
WIRE 16 -1 (-1000 700)(-2225 700);
FORCEPROP 2 LAST SIG_NAME P5E_CPU1_P0_TX_BUF_C_DP<12>
J 0
(-2085 710);
DISPLAY 0.638298 (-2085 710);
WIRE 16 -1 (-1000 850)(-2225 850);
FORCEPROP 2 LAST SIG_NAME P5E_CPU1_P1_RX_BUF_DP<12>
J 0
(-2085 860);
DISPLAY 0.638298 (-2085 860);
WIRE 16 -1 (-1000 1450)(-2225 1450);
FORCEPROP 2 LAST SIG_NAME P5E_CPU1_P1_TX_BUF_C_DN<13>
J 0
(-2085 1460);
DISPLAY 0.638298 (-2085 1460);
WIRE 16 -1 (-1000 1700)(-2225 1700);
FORCEPROP 2 LAST SIG_NAME P5E_CPU1_P1_RX_BUF_DP<13>
J 0
(-2085 1710);
DISPLAY 0.638298 (-2085 1710);
WIRE 16 -1 (-1000 2150)(-2225 2150);
FORCEPROP 2 LAST SIG_NAME P5E_CPU1_P1_TX_BUF_C_DP<14>
J 0
(-2085 2160);
DISPLAY 0.638298 (-2085 2160);
WIRE 16 -1 (-1000 2300)(-2225 2300);
FORCEPROP 2 LAST SIG_NAME P5E_CPU1_P0_TX_BUF_C_DP<14>
J 0
(-2085 2310);
DISPLAY 0.638298 (-2085 2310);
WIRE 16 -1 (-1000 2600)(-2225 2600);
FORCEPROP 2 LAST SIG_NAME P5E_CPU1_P0_RX_BUF_DP<14>
J 0
(-2085 2610);
DISPLAY 0.638298 (-2085 2610);
WIRE 16 -1 (-1000 3000)(-2225 3000);
FORCEPROP 2 LAST SIG_NAME P5E_CPU1_P1_TX_BUF_C_DP<15>
J 0
(-2085 3010);
DISPLAY 0.638298 (-2085 3010);
WIRE 16 -1 (-1000 3050)(-2225 3050);
FORCEPROP 2 LAST SIG_NAME P5E_CPU1_P1_TX_BUF_C_DN<15>
J 0
(-2085 3060);
DISPLAY 0.638298 (-2085 3060);
WIRE 16 -1 (-1000 3150)(-2225 3150);
FORCEPROP 2 LAST SIG_NAME P5E_CPU1_P0_TX_BUF_C_DP<15>
J 0
(-2085 3160);
DISPLAY 0.638298 (-2085 3160);
WIRE 16 -1 (-1000 3200)(-2225 3200);
FORCEPROP 2 LAST SIG_NAME P5E_CPU1_P0_TX_BUF_C_DN<15>
J 0
(-2085 3210);
DISPLAY 0.638298 (-2085 3210);
WIRE 16 -1 (-1000 3350)(-2225 3350);
FORCEPROP 2 LAST SIG_NAME P5E_CPU1_P1_RX_BUF_DN<15>
J 0
(-2085 3360);
DISPLAY 0.638298 (-2085 3360);
WIRE 16 -1 (-1000 3300)(-2225 3300);
FORCEPROP 2 LAST SIG_NAME P5E_CPU1_P1_RX_BUF_DP<15>
J 0
(-2085 3310);
DISPLAY 0.638298 (-2085 3310);
WIRE 16 -1 (3750 2450)(2500 2450);
FORCEPROP 2 LAST SIG_NAME P5E_CPU1_P1_RX_BUF_DP<10>
J 0
(2640 2460);
DISPLAY 0.638298 (2640 2460);
WIRE 16 -1 (3750 600)(2500 600);
FORCEPROP 2 LAST SIG_NAME P5E_CPU1_P1_TX_BUF_C_DN<8>
J 0
(2640 610);
DISPLAY 0.638298 (2640 610);
WIRE 16 -1 (-1000 2200)(-2225 2200);
FORCEPROP 2 LAST SIG_NAME P5E_CPU1_P1_TX_BUF_C_DN<14>
J 0
(-2085 2210);
DISPLAY 0.638298 (-2085 2210);
WIRE 16 -1 (3750 3500)(2500 3500);
FORCEPROP 2 LAST SIG_NAME P5E_CPU1_P0_RX_BUF_DN<11>
J 0
(2640 3510);
DISPLAY 0.638298 (2640 3510);
WIRE 16 -1 (3750 3450)(2500 3450);
FORCEPROP 2 LAST SIG_NAME P5E_CPU1_P0_RX_BUF_DP<11>
J 0
(2640 3460);
DISPLAY 0.638298 (2640 3460);
WIRE 16 -1 (3750 3300)(2500 3300);
FORCEPROP 2 LAST SIG_NAME P5E_CPU1_P1_RX_BUF_DP<11>
J 0
(2640 3310);
DISPLAY 0.638298 (2640 3310);
WIRE 16 -1 (3750 3350)(2500 3350);
FORCEPROP 2 LAST SIG_NAME P5E_CPU1_P1_RX_BUF_DN<11>
J 0
(2640 3360);
DISPLAY 0.638298 (2640 3360);
WIRE 16 -1 (-1000 1000)(-2225 1000);
FORCEPROP 2 LAST SIG_NAME P5E_CPU1_P0_RX_BUF_DP<12>
J 0
(-2085 1010);
DISPLAY 0.638298 (-2085 1010);
WIRE 16 -1 (-1000 900)(-2225 900);
FORCEPROP 2 LAST SIG_NAME P5E_CPU1_P1_RX_BUF_DN<12>
J 0
(-2085 910);
DISPLAY 0.638298 (-2085 910);
WIRE 16 -1 (-1000 750)(-2225 750);
FORCEPROP 2 LAST SIG_NAME P5E_CPU1_P0_TX_BUF_C_DN<12>
J 0
(-2085 760);
DISPLAY 0.638298 (-2085 760);
WIRE 16 -1 (-1000 3450)(-2225 3450);
FORCEPROP 2 LAST SIG_NAME P5E_CPU1_P0_RX_BUF_DP<15>
J 0
(-2085 3460);
DISPLAY 0.638298 (-2085 3460);
WIRE 16 -1 (-1000 3500)(-2225 3500);
FORCEPROP 2 LAST SIG_NAME P5E_CPU1_P0_RX_BUF_DN<15>
J 0
(-2085 3510);
DISPLAY 0.638298 (-2085 3510);
DOT 1 (3525 1350);
DOT 1 (3525 2700);
DOT 1 (-1175 2550);
DOT 1 (-1175 2400);
DOT 1 (-1175 2100);
DOT 1 (-1175 1950);
DOT 1 (-1175 3100);
DOT 1 (-1175 500);
DOT 1 (-1175 650);
DOT 1 (-1175 800);
DOT 1 (-1175 950);
DOT 1 (-1175 1100);
DOT 1 (-1175 1500);
DOT 1 (-1175 1350);
DOT 1 (-1175 1650);
DOT 1 (-1175 1800);
DOT 1 (-1175 2250);
DOT 1 (-1175 2700);
DOT 1 (-1175 3250);
DOT 1 (-1175 3400);
DOT 1 (3525 500);
DOT 1 (3525 650);
DOT 1 (3525 800);
DOT 1 (3525 1100);
DOT 1 (3525 950);
DOT 1 (3525 1500);
DOT 1 (3525 1650);
DOT 1 (3525 1800);
DOT 1 (3525 1950);
DOT 1 (3525 2100);
DOT 1 (3525 2250);
DOT 1 (3525 2550);
DOT 1 (3525 2400);
DOT 1 (3525 2950);
DOT 1 (3525 3100);
DOT 1 (3525 3250);
DOT 1 (3525 3400);
DOT 1 (-1175 2950);
FORCENOTE
CPU1_P0_TX/RX<0-15> LANE REVERSAL
(-3525 4425) 0;
DISPLAY LEFT (-3525 4425);
DISPLAY 1.595745 (-3525 4425);
PAINT PINK (-3525 4425);
FORCENOTE
CPU1_P1_TX/RX<0-15> LANE REVERSAL
(-3525 4325) 0;
DISPLAY LEFT (-3525 4325);
DISPLAY 1.595745 (-3525 4325);
PAINT PINK (-3525 4325);
QUIT
